G04 ================== begin FILE IDENTIFICATION RECORD ==================*
G04 Layout Name:  15105-sa.brd*
G04 Film Name:    DRILL*
G04 File Format:  Gerber RS274X*
G04 File Origin:  Cadence Allegro 16.5-S056*
G04 Origin Date:  Wed Nov 16 02:01:51 2016*
G04 *
G04 Layer:  MANUFACTURING/NCLEGEND-1-8*
G04 Layer:  MANUFACTURING/DRILL SIZE*
G04 Layer:  DRAWING FORMAT/LAYER_PCB_STORY*
G04 Layer:  DRAWING FORMAT/LAYER_DRILL*
G04 Layer:  BOARD GEOMETRY/PANEL_OUTLINE*
G04 *
G04 Offset:    (0.00 0.00)*
G04 Mirror:    No*
G04 Mode:      Positive*
G04 Rotation:  0*
G04 FullContactRelief:  No*
G04 UndefLineWidth:     6.00*
G04 ================== end FILE IDENTIFICATION RECORD ====================*
%FSLAX35Y35*MOIN*%
%IR0*IPPOS*OFA0.00000B0.00000*MIA0B0*SFA1.00000B1.00000*%
%AMMACRO30*
1,1,.006,0.0,.00728*
20,1,.006,0.0,.00728,-.006305,.00364,0.0*
1,1,.006,-.006305,.00364*
20,1,.006,-.006305,.00364,-.006305,-.00364,0.0*
1,1,.006,-.006305,-.00364*
20,1,.006,-.006305,-.00364,0.0,-.00728,0.0*
1,1,.006,0.0,-.00728*
20,1,.006,0.0,-.00728,.006305,-.00364,0.0*
1,1,.006,.006305,-.00364*
20,1,.006,.006305,-.00364,.006305,.00364,0.0*
1,1,.006,.006305,.00364*
20,1,.006,.006305,.00364,0.0,.00728,0.0*
1,1,.006,0.0,.00728*
1,1,.006,.00146,-.00364*
20,1,.006,.00146,-.00364,.00146,.00364,0.0*
1,1,.006,.00146,.00364*
20,1,.006,.00146,.00364,-.00303,-.00158,0.0*
1,1,.006,-.00303,-.00158*
20,1,.006,-.00303,-.00158,.00303,-.00158,0.0*
1,1,.006,.00303,-.00158*
%
%ADD30MACRO30*%
%AMMACRO11*
1,1,.006,.005,.005*
20,1,.006,.005,.005,.005,-.005,0.0*
1,1,.006,.005,-.005*
20,1,.006,.005,-.005,-.005,-.005,0.0*
1,1,.006,-.005,-.005*
20,1,.006,-.005,-.005,-.005,.005,0.0*
1,1,.006,-.005,.005*
20,1,.006,-.005,.005,.005,.005,0.0*
1,1,.006,.005,.005*
1,1,.006,-.00158,.00167*
20,1,.006,-.00158,.00167,-.00108,.00217,0.0*
1,1,.006,-.00108,.00217*
20,1,.006,-.00108,.00217,-.0005,.00242,0.0*
1,1,.006,-.0005,.00242*
20,1,.006,-.0005,.00242,.00017,.0025,0.0*
1,1,.006,.00017,.0025*
20,1,.006,.00017,.0025,.001,.00233,0.0*
1,1,.006,.001,.00233*
20,1,.006,.001,.00233,.00158,.00192,0.0*
1,1,.006,.00158,.00192*
20,1,.006,.00158,.00192,.00175,.00142,0.0*
1,1,.006,.00175,.00142*
20,1,.006,.00175,.00142,.00167,.00092,0.0*
1,1,.006,.00167,.00092*
20,1,.006,.00167,.00092,.00133,.0005,0.0*
1,1,.006,.00133,.0005*
20,1,.006,.00133,.0005,-.00033,-.00033,0.0*
1,1,.006,-.00033,-.00033*
20,1,.006,-.00033,-.00033,-.00108,-.00092,0.0*
1,1,.006,-.00108,-.00092*
20,1,.006,-.00108,-.00092,-.00158,-.00175,0.0*
1,1,.006,-.00158,-.00175*
20,1,.006,-.00158,-.00175,-.00175,-.0025,0.0*
1,1,.006,-.00175,-.0025*
20,1,.006,-.00175,-.0025,.00175,-.0025,0.0*
1,1,.006,.00175,-.0025*
%
%ADD11MACRO11*%
%AMMACRO23*
1,1,.006,.003314,-.008*
20,1,.006,.003314,-.008,-.003314,-.008,0.0*
1,1,.006,-.003314,-.008*
20,1,.006,-.003314,-.008,-.008,-.003314,0.0*
1,1,.006,-.008,-.003314*
20,1,.006,-.008,-.003314,-.008,.003314,0.0*
1,1,.006,-.008,.003314*
20,1,.006,-.008,.003314,-.003314,.008,0.0*
1,1,.006,-.003314,.008*
20,1,.006,-.003314,.008,.003314,.008,0.0*
1,1,.006,.003314,.008*
20,1,.006,.003314,.008,.008,.003314,0.0*
1,1,.006,.008,.003314*
20,1,.006,.008,.003314,.008,-.003314,0.0*
1,1,.006,.008,-.003314*
20,1,.006,.008,-.003314,.003314,-.008,0.0*
1,1,.006,.003314,-.008*
1,1,.006,-.00293,-.0028*
20,1,.006,-.00293,-.0028,-.00213,-.00347,0.0*
1,1,.006,-.00213,-.00347*
20,1,.006,-.00213,-.00347,-.0012,-.00387,0.0*
1,1,.006,-.0012,-.00387*
20,1,.006,-.0012,-.00387,0.0,-.004,0.0*
1,1,.006,0.0,-.004*
20,1,.006,0.0,-.004,.0012,-.00373,0.0*
1,1,.006,.0012,-.00373*
20,1,.006,.0012,-.00373,.00213,-.0032,0.0*
1,1,.006,.00213,-.0032*
20,1,.006,.00213,-.0032,.0028,-.00227,0.0*
1,1,.006,.0028,-.00227*
20,1,.006,.0028,-.00227,.00293,-.0012,0.0*
1,1,.006,.00293,-.0012*
20,1,.006,.00293,-.0012,.00267,-.00013,0.0*
1,1,.006,.00267,-.00013*
20,1,.006,.00267,-.00013,.002,.00053,0.0*
1,1,.006,.002,.00053*
20,1,.006,.002,.00053,.00107,.00107,0.0*
1,1,.006,.00107,.00107*
20,1,.006,.00107,.00107,.00013,.0012,0.0*
1,1,.006,.00013,.0012*
20,1,.006,.00013,.0012,-.0008,.00107,0.0*
1,1,.006,-.0008,.00107*
20,1,.006,-.0008,.00107,-.002,.00053,0.0*
1,1,.006,-.002,.00053*
20,1,.006,-.002,.00053,-.0016,.004,0.0*
1,1,.006,-.0016,.004*
20,1,.006,-.0016,.004,.002,.004,0.0*
1,1,.006,.002,.004*
%
%ADD23MACRO23*%
%AMMACRO22*
1,1,.006,.004,0.0*
20,1,.006,.004,0.0,-.004,0.0,0.0*
1,1,.006,-.004,0.0*
1,1,.006,0.0,.004*
20,1,.006,0.0,.004,0.0,-.004,0.0*
1,1,.006,0.0,-.004*
1,1,.006,.002,0.0*
20,1,.006,.002,0.0,.002,.004,0.0*
1,1,.006,.002,.004*
20,1,.006,.002,.004,.0012,.0032,0.0*
1,1,.006,.0012,.0032*
1,1,.006,.0012,0.0*
20,1,.006,.0012,0.0,.0028,0.0,0.0*
1,1,.006,.0028,0.0*
%
%ADD22MACRO22*%
%AMMACRO12*
1,1,.006,.00667,.00167*
20,1,.006,.00667,.00167,.01,.00417,0.0*
1,1,.006,.01,.00417*
20,1,.006,.01,.00417,.0125,.00833,0.0*
1,1,.006,.0125,.00833*
20,1,.006,.0125,.00833,.01417,.01417,0.0*
1,1,.006,.01417,.01417*
20,1,.006,.01417,.01417,.0125,.01917,0.0*
1,1,.006,.0125,.01917*
20,1,.006,.0125,.01917,.00917,.0225,0.0*
1,1,.006,.00917,.0225*
20,1,.006,.00917,.0225,.00333,.025,0.0*
1,1,.006,.00333,.025*
20,1,.006,.00333,.025,-.01917,.025,0.0*
1,1,.006,-.01917,.025*
20,1,.006,-.01917,.025,-.01917,-.025,0.0*
1,1,.006,-.01917,-.025*
20,1,.006,-.01917,-.025,.00833,-.025,0.0*
1,1,.006,.00833,-.025*
20,1,.006,.00833,-.025,.01417,-.02167,0.0*
1,1,.006,.01417,-.02167*
20,1,.006,.01417,-.02167,.0175,-.01667,0.0*
1,1,.006,.0175,-.01667*
20,1,.006,.0175,-.01667,.01917,-.01083,0.0*
1,1,.006,.01917,-.01083*
20,1,.006,.01917,-.01083,.0175,-.005,0.0*
1,1,.006,.0175,-.005*
20,1,.006,.0175,-.005,.0125,0.0,0.0*
1,1,.006,.0125,0.0*
20,1,.006,.0125,0.0,.00667,.00167,0.0*
1,1,.006,.00667,.00167*
20,1,.006,.00667,.00167,-.01917,.00167,0.0*
1,1,.006,-.01917,.00167*
%
%ADD12MACRO12*%
%AMMACRO27*
1,1,.006,-.0175,-.021*
20,1,.006,-.0175,-.021,0.0,.021,0.0*
1,1,.006,0.0,.021*
20,1,.006,0.0,.021,.0175,-.021,0.0*
1,1,.006,.0175,-.021*
1,1,.006,.0112,-.0063*
20,1,.006,.0112,-.0063,-.0112,-.0063,0.0*
1,1,.006,-.0112,-.0063*
%
%ADD27MACRO27*%
%AMMACRO14*
1,1,.006,.015,0.0*
20,1,.006,.015,0.0,.065,0.0,0.0*
1,1,.006,.065,0.0*
20,1,.006,.065,0.0,.065,-.045,0.0*
1,1,.006,.065,-.045*
20,1,.006,.065,-.045,.05,-.06,0.0*
1,1,.006,.05,-.06*
20,1,.006,.05,-.06,.0325,-.07,0.0*
1,1,.006,.0325,-.07*
20,1,.006,.0325,-.07,.0075,-.075,0.0*
1,1,.006,.0075,-.075*
20,1,.006,.0075,-.075,-.0175,-.07,0.0*
1,1,.006,-.0175,-.07*
20,1,.006,-.0175,-.07,-.035,-.06,0.0*
1,1,.006,-.035,-.06*
20,1,.006,-.035,-.06,-.05,-.045,0.0*
1,1,.006,-.05,-.045*
20,1,.006,-.05,-.045,-.06,-.0275,0.0*
1,1,.006,-.06,-.0275*
20,1,.006,-.06,-.0275,-.065,-.0075,0.0*
1,1,.006,-.065,-.0075*
20,1,.006,-.065,-.0075,-.065,.01,0.0*
1,1,.006,-.065,.01*
20,1,.006,-.065,.01,-.06,.025,0.0*
1,1,.006,-.06,.025*
20,1,.006,-.06,.025,-.05,.0425,0.0*
1,1,.006,-.05,.0425*
20,1,.006,-.05,.0425,-.035,.0575,0.0*
1,1,.006,-.035,.0575*
20,1,.006,-.035,.0575,-.02,.0675,0.0*
1,1,.006,-.02,.0675*
20,1,.006,-.02,.0675,0.0,.075,0.0*
1,1,.006,0.0,.075*
20,1,.006,0.0,.075,.0175,.075,0.0*
1,1,.006,.0175,.075*
20,1,.006,.0175,.075,.0375,.07,0.0*
1,1,.006,.0375,.07*
20,1,.006,.0375,.07,.0525,.06,0.0*
1,1,.006,.0525,.06*
%
%ADD14MACRO14*%
%AMMACRO31*
1,1,.006,-.01467,-.02*
20,1,.006,-.01467,-.02,-.01467,.02,0.0*
1,1,.006,-.01467,.02*
1,1,.006,.01067,.02*
20,1,.006,.01067,.02,-.01467,-.00467,0.0*
1,1,.006,-.01467,-.00467*
1,1,.006,.01467,-.02*
20,1,.006,.01467,-.02,-.00333,.00667,0.0*
1,1,.006,-.00333,.00667*
%
%ADD31MACRO31*%
%AMMACRO25*
1,1,.006,-.0399,-.063*
20,1,.006,-.0399,-.063,-.0399,.063,0.0*
1,1,.006,-.0399,.063*
20,1,.006,-.0399,.063,.0399,.063,0.0*
1,1,.006,.0399,.063*
1,1,.006,.0105,.0021*
20,1,.006,.0105,.0021,-.0399,.0021,0.0*
1,1,.006,-.0399,.0021*
%
%ADD25MACRO25*%
%AMMACRO18*
1,1,.006,-.0064,.016*
20,1,.006,-.0064,.016,.0064,.016,0.0*
1,1,.006,.0064,.016*
1,1,.006,0.0,.016*
20,1,.006,0.0,.016,0.0,-.016,0.0*
1,1,.006,0.0,-.016*
1,1,.006,-.0064,-.016*
20,1,.006,-.0064,-.016,.0064,-.016,0.0*
1,1,.006,.0064,-.016*
%
%ADD18MACRO18*%
%AMMACRO13*
1,1,.006,.02273,.02583*
20,1,.006,.02273,.02583,.01653,.02893,0.0*
1,1,.006,.01653,.02893*
20,1,.006,.01653,.02893,.0093,.031,0.0*
1,1,.006,.0093,.031*
20,1,.006,.0093,.031,.00103,.031,0.0*
1,1,.006,.00103,.031*
20,1,.006,.00103,.031,-.00827,.0279,0.0*
1,1,.006,-.00827,.0279*
20,1,.006,-.00827,.0279,-.0155,.02273,0.0*
1,1,.006,-.0155,.02273*
20,1,.006,-.0155,.02273,-.02067,.01653,0.0*
1,1,.006,-.02067,.01653*
20,1,.006,-.02067,.01653,-.0248,.0062,0.0*
1,1,.006,-.0248,.0062*
20,1,.006,-.0248,.0062,-.02583,-.0031,0.0*
1,1,.006,-.02583,-.0031*
20,1,.006,-.02583,-.0031,-.02377,-.0124,0.0*
1,1,.006,-.02377,-.0124*
20,1,.006,-.02377,-.0124,-.02067,-.0186,0.0*
1,1,.006,-.02067,-.0186*
20,1,.006,-.02067,-.0186,-.01447,-.0248,0.0*
1,1,.006,-.01447,-.0248*
20,1,.006,-.01447,-.0248,-.00723,-.02893,0.0*
1,1,.006,-.00723,-.02893*
20,1,.006,-.00723,-.02893,0.0,-.031,0.0*
1,1,.006,0.0,-.031*
20,1,.006,0.0,-.031,.00723,-.031,0.0*
1,1,.006,.00723,-.031*
20,1,.006,.00723,-.031,.01447,-.02893,0.0*
1,1,.006,.01447,-.02893*
20,1,.006,.01447,-.02893,.02067,-.02583,0.0*
1,1,.006,.02067,-.02583*
20,1,.006,.02067,-.02583,.02583,-.0217,0.0*
1,1,.006,.02583,-.0217*
%
%ADD13MACRO13*%
%AMMACRO28*
1,1,.006,.01122,0.0*
20,1,.006,.01122,0.0,0.0,-.01122,0.0*
1,1,.006,0.0,-.01122*
20,1,.006,0.0,-.01122,-.01122,0.0,0.0*
1,1,.006,-.01122,0.0*
20,1,.006,-.01122,0.0,0.0,.01122,0.0*
1,1,.006,0.0,.01122*
20,1,.006,0.0,.01122,.01122,0.0,0.0*
1,1,.006,.01122,0.0*
1,1,.006,-.00355,-.00094*
20,1,.006,-.00355,-.00094,-.00224,.00037,0.0*
1,1,.006,-.00224,.00037*
20,1,.006,-.00224,.00037,-.00112,.00112,0.0*
1,1,.006,-.00112,.00112*
20,1,.006,-.00112,.00112,.00037,.0015,0.0*
1,1,.006,.00037,.0015*
20,1,.006,.00037,.0015,.00168,.00112,0.0*
1,1,.006,.00168,.00112*
20,1,.006,.00168,.00112,.00262,.00037,0.0*
1,1,.006,.00262,.00037*
20,1,.006,.00262,.00037,.00337,-.00075,0.0*
1,1,.006,.00337,-.00075*
20,1,.006,.00337,-.00075,.00355,-.00206,0.0*
1,1,.006,.00355,-.00206*
20,1,.006,.00355,-.00206,.00337,-.00318,0.0*
1,1,.006,.00337,-.00318*
20,1,.006,.00337,-.00318,.00262,-.0043,0.0*
1,1,.006,.00262,-.0043*
20,1,.006,.00262,-.0043,.0015,-.00524,0.0*
1,1,.006,.0015,-.00524*
20,1,.006,.0015,-.00524,.00019,-.00561,0.0*
1,1,.006,.00019,-.00561*
20,1,.006,.00019,-.00561,-.00131,-.00524,0.0*
1,1,.006,-.00131,-.00524*
20,1,.006,-.00131,-.00524,-.00262,-.00411,0.0*
1,1,.006,-.00262,-.00411*
20,1,.006,-.00262,-.00411,-.00337,-.00243,0.0*
1,1,.006,-.00337,-.00243*
20,1,.006,-.00337,-.00243,-.00355,-.00056,0.0*
1,1,.006,-.00355,-.00056*
20,1,.006,-.00355,-.00056,-.00318,.00187,0.0*
1,1,.006,-.00318,.00187*
20,1,.006,-.00318,.00187,-.00262,.00318,0.0*
1,1,.006,-.00262,.00318*
20,1,.006,-.00262,.00318,-.00168,.00449,0.0*
1,1,.006,-.00168,.00449*
20,1,.006,-.00168,.00449,-.00037,.00542,0.0*
1,1,.006,-.00037,.00542*
20,1,.006,-.00037,.00542,.00093,.00561,0.0*
1,1,.006,.00093,.00561*
20,1,.006,.00093,.00561,.00224,.00524,0.0*
1,1,.006,.00224,.00524*
20,1,.006,.00224,.00524,.00318,.0043,0.0*
1,1,.006,.00318,.0043*
%
%ADD28MACRO28*%
%AMMACRO19*
1,1,.006,.03033,-.0455*
20,1,.006,.03033,-.0455,-.03033,-.0455,0.0*
1,1,.006,-.03033,-.0455*
20,1,.006,-.03033,-.0455,-.03033,.0455,0.0*
1,1,.006,-.03033,.0455*
20,1,.006,-.03033,.0455,.03033,.0455,0.0*
1,1,.006,.03033,.0455*
1,1,.006,.00607,.00152*
20,1,.006,.00607,.00152,-.03033,.00152,0.0*
1,1,.006,-.03033,.00152*
%
%ADD19MACRO19*%
%AMMACRO15*
1,1,.006,-.05547,-.064*
20,1,.006,-.05547,-.064,-.05547,.064,0.0*
1,1,.006,-.05547,.064*
20,1,.006,-.05547,.064,0.0,-.04267,0.0*
1,1,.006,0.0,-.04267*
20,1,.006,0.0,-.04267,.05547,.064,0.0*
1,1,.006,.05547,.064*
20,1,.006,.05547,.064,.05547,-.064,0.0*
1,1,.006,.05547,-.064*
%
%ADD15MACRO15*%
%AMMACRO33*
1,1,.006,-.01267,-.0114*
20,1,.006,-.01267,-.0114,-.0095,-.0152,0.0*
1,1,.006,-.0095,-.0152*
20,1,.006,-.0095,-.0152,-.0057,-.01773,0.0*
1,1,.006,-.0057,-.01773*
20,1,.006,-.0057,-.01773,-.00127,-.019,0.0*
1,1,.006,-.00127,-.019*
20,1,.006,-.00127,-.019,.0038,-.01773,0.0*
1,1,.006,.0038,-.01773*
20,1,.006,.0038,-.01773,.0076,-.0152,0.0*
1,1,.006,.0076,-.0152*
20,1,.006,.0076,-.0152,.0114,-.0114,0.0*
1,1,.006,.0114,-.0114*
20,1,.006,.0114,-.0114,.01267,-.00633,0.0*
1,1,.006,.01267,-.00633*
20,1,.006,.01267,-.00633,.01267,.019,0.0*
1,1,.006,.01267,.019*
%
%ADD33MACRO33*%
%AMMACRO17*
1,1,.006,-.0588,-.084*
20,1,.006,-.0588,-.084,-.0588,.084,0.0*
1,1,.006,-.0588,.084*
1,1,.006,.0588,.084*
20,1,.006,.0588,.084,.0588,-.084,0.0*
1,1,.006,.0588,-.084*
1,1,.006,.0588,0.0*
20,1,.006,.0588,0.0,-.0588,0.0,0.0*
1,1,.006,-.0588,0.0*
%
%ADD17MACRO17*%
%AMMACRO29*
1,1,.006,-.0319,-.0435*
20,1,.006,-.0319,-.0435,-.0319,.0435,0.0*
1,1,.006,-.0319,.0435*
20,1,.006,-.0319,.0435,-.0029,.0435,0.0*
1,1,.006,-.0029,.0435*
20,1,.006,-.0029,.0435,.0087,.03915,0.0*
1,1,.006,.0087,.03915*
20,1,.006,.0087,.03915,.0174,.03335,0.0*
1,1,.006,.0174,.03335*
20,1,.006,.0174,.03335,.02465,.02465,0.0*
1,1,.006,.02465,.02465*
20,1,.006,.02465,.02465,.03045,.0145,0.0*
1,1,.006,.03045,.0145*
20,1,.006,.03045,.0145,.0319,0.0,0.0*
1,1,.006,.0319,0.0*
20,1,.006,.0319,0.0,.03045,-.0145,0.0*
1,1,.006,.03045,-.0145*
20,1,.006,.03045,-.0145,.02465,-.02465,0.0*
1,1,.006,.02465,-.02465*
20,1,.006,.02465,-.02465,.0174,-.03335,0.0*
1,1,.006,.0174,-.03335*
20,1,.006,.0174,-.03335,.0087,-.03915,0.0*
1,1,.006,.0087,-.03915*
20,1,.006,.0087,-.03915,-.0029,-.0435,0.0*
1,1,.006,-.0029,-.0435*
20,1,.006,-.0029,-.0435,-.0319,-.0435,0.0*
1,1,.006,-.0319,-.0435*
%
%ADD29MACRO29*%
%AMMACRO10*
1,1,.006,-.02867,.043*
20,1,.006,-.02867,.043,-.02867,-.043,0.0*
1,1,.006,-.02867,-.043*
20,1,.006,-.02867,-.043,.02867,-.043,0.0*
1,1,.006,.02867,-.043*
%
%ADD10MACRO10*%
%AMMACRO24*
1,1,.006,.02,0.0*
20,1,.006,.02,0.0,.019696,-.003473,0.0*
1,1,.006,.019696,-.003473*
20,1,.006,.019696,-.003473,.018794,-.00684,0.0*
1,1,.006,.018794,-.00684*
20,1,.006,.018794,-.00684,.017321,-.01,0.0*
1,1,.006,.017321,-.01*
20,1,.006,.017321,-.01,.015321,-.012856,0.0*
1,1,.006,.015321,-.012856*
20,1,.006,.015321,-.012856,.012856,-.015321,0.0*
1,1,.006,.012856,-.015321*
20,1,.006,.012856,-.015321,.01,-.017321,0.0*
1,1,.006,.01,-.017321*
20,1,.006,.01,-.017321,.00684,-.018794,0.0*
1,1,.006,.00684,-.018794*
20,1,.006,.00684,-.018794,.003473,-.019696,0.0*
1,1,.006,.003473,-.019696*
20,1,.006,.003473,-.019696,0.0,-.02,0.0*
1,1,.006,0.0,-.02*
20,1,.006,0.0,-.02,-.003473,-.019696,0.0*
1,1,.006,-.003473,-.019696*
20,1,.006,-.003473,-.019696,-.00684,-.018794,0.0*
1,1,.006,-.00684,-.018794*
20,1,.006,-.00684,-.018794,-.01,-.017321,0.0*
1,1,.006,-.01,-.017321*
20,1,.006,-.01,-.017321,-.012856,-.015321,0.0*
1,1,.006,-.012856,-.015321*
20,1,.006,-.012856,-.015321,-.015321,-.012856,0.0*
1,1,.006,-.015321,-.012856*
20,1,.006,-.015321,-.012856,-.017321,-.01,0.0*
1,1,.006,-.017321,-.01*
20,1,.006,-.017321,-.01,-.018794,-.00684,0.0*
1,1,.006,-.018794,-.00684*
20,1,.006,-.018794,-.00684,-.019696,-.003473,0.0*
1,1,.006,-.019696,-.003473*
20,1,.006,-.019696,-.003473,-.02,0.0,0.0*
1,1,.006,-.02,0.0*
20,1,.006,-.02,0.0,-.019696,.003473,0.0*
1,1,.006,-.019696,.003473*
20,1,.006,-.019696,.003473,-.018794,.00684,0.0*
1,1,.006,-.018794,.00684*
20,1,.006,-.018794,.00684,-.017321,.01,0.0*
1,1,.006,-.017321,.01*
20,1,.006,-.017321,.01,-.015321,.012856,0.0*
1,1,.006,-.015321,.012856*
20,1,.006,-.015321,.012856,-.012856,.015321,0.0*
1,1,.006,-.012856,.015321*
20,1,.006,-.012856,.015321,-.01,.017321,0.0*
1,1,.006,-.01,.017321*
20,1,.006,-.01,.017321,-.00684,.018794,0.0*
1,1,.006,-.00684,.018794*
20,1,.006,-.00684,.018794,-.003473,.019696,0.0*
1,1,.006,-.003473,.019696*
20,1,.006,-.003473,.019696,0.0,.02,0.0*
1,1,.006,0.0,.02*
20,1,.006,0.0,.02,.003473,.019696,0.0*
1,1,.006,.003473,.019696*
20,1,.006,.003473,.019696,.00684,.018794,0.0*
1,1,.006,.00684,.018794*
20,1,.006,.00684,.018794,.01,.017321,0.0*
1,1,.006,.01,.017321*
20,1,.006,.01,.017321,.012856,.015321,0.0*
1,1,.006,.012856,.015321*
20,1,.006,.012856,.015321,.015321,.012856,0.0*
1,1,.006,.015321,.012856*
20,1,.006,.015321,.012856,.017321,.01,0.0*
1,1,.006,.017321,.01*
20,1,.006,.017321,.01,.018794,.00684,0.0*
1,1,.006,.018794,.00684*
20,1,.006,.018794,.00684,.019696,.003473,0.0*
1,1,.006,.019696,.003473*
20,1,.006,.019696,.003473,.02,0.0,0.0*
1,1,.006,.02,0.0*
1,1,.006,-.01,-.01*
20,1,.006,-.01,-.01,-.01,.01,0.0*
1,1,.006,-.01,.01*
20,1,.006,-.01,.01,-.014,.006,0.0*
1,1,.006,-.014,.006*
1,1,.006,-.014,-.01*
20,1,.006,-.014,-.01,-.006,-.01,0.0*
1,1,.006,-.006,-.01*
1,1,.006,.01001,-.01*
20,1,.006,.01001,-.01,.01001,.01,0.0*
1,1,.006,.01001,.01*
20,1,.006,.01001,.01,.00601,.006,0.0*
1,1,.006,.00601,.006*
1,1,.006,.00601,-.01*
20,1,.006,.00601,-.01,.01401,-.01,0.0*
1,1,.006,.01401,-.01*
%
%ADD24MACRO24*%
%AMMACRO21*
1,1,.006,.006,0.0*
20,1,.006,.006,0.0,.003,.005196,0.0*
1,1,.006,.003,.005196*
20,1,.006,.003,.005196,-.003,.005196,0.0*
1,1,.006,-.003,.005196*
20,1,.006,-.003,.005196,-.006,0.0,0.0*
1,1,.006,-.006,0.0*
20,1,.006,-.006,0.0,-.003,-.005196,0.0*
1,1,.006,-.003,-.005196*
20,1,.006,-.003,-.005196,.003,-.005196,0.0*
1,1,.006,.003,-.005196*
20,1,.006,.003,-.005196,.006,0.0,0.0*
1,1,.006,.006,0.0*
1,1,.006,-.0022,-.0018*
20,1,.006,-.0022,-.0018,-.0016,-.0025,0.0*
1,1,.006,-.0016,-.0025*
20,1,.006,-.0016,-.0025,-.0008,-.0029,0.0*
1,1,.006,-.0008,-.0029*
20,1,.006,-.0008,-.0029,.0001,-.003,0.0*
1,1,.006,.0001,-.003*
20,1,.006,.0001,-.003,.0009,-.0029,0.0*
1,1,.006,.0009,-.0029*
20,1,.006,.0009,-.0029,.0017,-.0024,0.0*
1,1,.006,.0017,-.0024*
20,1,.006,.0017,-.0024,.0022,-.0018,0.0*
1,1,.006,.0022,-.0018*
20,1,.006,.0022,-.0018,.0023,-.0012,0.0*
1,1,.006,.0023,-.0012*
20,1,.006,.0023,-.0012,.0021,-.0005,0.0*
1,1,.006,.0021,-.0005*
20,1,.006,.0021,-.0005,.0014,0.0,0.0*
1,1,.006,.0014,0.0*
20,1,.006,.0014,0.0,.0007,.0002,0.0*
1,1,.006,.0007,.0002*
20,1,.006,.0007,.0002,-.0002,.0002,0.0*
1,1,.006,-.0002,.0002*
1,1,.006,.0007,.0002*
20,1,.006,.0007,.0002,.0013,.0005,0.0*
1,1,.006,.0013,.0005*
20,1,.006,.0013,.0005,.0018,.001,0.0*
1,1,.006,.0018,.001*
20,1,.006,.0018,.001,.002,.0016,0.0*
1,1,.006,.002,.0016*
20,1,.006,.002,.0016,.0018,.0022,0.0*
1,1,.006,.0018,.0022*
20,1,.006,.0018,.0022,.0013,.0027,0.0*
1,1,.006,.0013,.0027*
20,1,.006,.0013,.0027,.0004,.003,0.0*
1,1,.006,.0004,.003*
20,1,.006,.0004,.003,-.0005,.0029,0.0*
1,1,.006,-.0005,.0029*
20,1,.006,-.0005,.0029,-.0014,.0025,0.0*
1,1,.006,-.0014,.0025*
%
%ADD21MACRO21*%
%AMMACRO26*
1,1,.006,0.0,.015*
20,1,.006,0.0,.015,.015,-.015,0.0*
1,1,.006,.015,-.015*
20,1,.006,.015,-.015,-.015,-.015,0.0*
1,1,.006,-.015,-.015*
20,1,.006,-.015,-.015,0.0,.015,0.0*
1,1,.006,0.0,.015*
1,1,.006,-.0005,-.0075*
20,1,.006,-.0005,-.0075,0.0,-.00425,0.0*
1,1,.006,0.0,-.00425*
20,1,.006,0.0,-.00425,.00075,-.0015,0.0*
1,1,.006,.00075,-.0015*
20,1,.006,.00075,-.0015,.00175,.001,0.0*
1,1,.006,.00175,.001*
20,1,.006,.00175,.001,.003,.00375,0.0*
1,1,.006,.003,.00375*
20,1,.006,.003,.00375,.005,.0075,0.0*
1,1,.006,.005,.0075*
20,1,.006,.005,.0075,-.005,.0075,0.0*
1,1,.006,-.005,.0075*
%
%ADD26MACRO26*%
%AMMACRO16*
1,1,.006,-.0135,.0045*
20,1,.006,-.0135,.0045,-.013295,.006844,0.0*
1,1,.006,-.013295,.006844*
20,1,.006,-.013295,.006844,-.012686,.009117,0.0*
1,1,.006,-.012686,.009117*
20,1,.006,-.012686,.009117,-.011691,.01125,0.0*
1,1,.006,-.011691,.01125*
20,1,.006,-.011691,.01125,-.010342,.013178,0.0*
1,1,.006,-.010342,.013178*
20,1,.006,-.010342,.013178,-.008678,.014842,0.0*
1,1,.006,-.008678,.014842*
20,1,.006,-.008678,.014842,-.00675,.016191,0.0*
1,1,.006,-.00675,.016191*
20,1,.006,-.00675,.016191,-.004617,.017186,0.0*
1,1,.006,-.004617,.017186*
20,1,.006,-.004617,.017186,-.002344,.017795,0.0*
1,1,.006,-.002344,.017795*
20,1,.006,-.002344,.017795,0.0,.018,0.0*
1,1,.006,0.0,.018*
20,1,.006,0.0,.018,.002344,.017795,0.0*
1,1,.006,.002344,.017795*
20,1,.006,.002344,.017795,.004617,.017186,0.0*
1,1,.006,.004617,.017186*
20,1,.006,.004617,.017186,.00675,.016191,0.0*
1,1,.006,.00675,.016191*
20,1,.006,.00675,.016191,.008678,.014842,0.0*
1,1,.006,.008678,.014842*
20,1,.006,.008678,.014842,.010342,.013178,0.0*
1,1,.006,.010342,.013178*
20,1,.006,.010342,.013178,.011691,.01125,0.0*
1,1,.006,.011691,.01125*
20,1,.006,.011691,.01125,.012686,.009117,0.0*
1,1,.006,.012686,.009117*
20,1,.006,.012686,.009117,.013295,.006844,0.0*
1,1,.006,.013295,.006844*
20,1,.006,.013295,.006844,.0135,.0045,0.0*
1,1,.006,.0135,.0045*
20,1,.006,.0135,.0045,.0135,-.0045,0.0*
1,1,.006,.0135,-.0045*
20,1,.006,.0135,-.0045,.013295,-.006844,0.0*
1,1,.006,.013295,-.006844*
20,1,.006,.013295,-.006844,.012686,-.009117,0.0*
1,1,.006,.012686,-.009117*
20,1,.006,.012686,-.009117,.011691,-.01125,0.0*
1,1,.006,.011691,-.01125*
20,1,.006,.011691,-.01125,.010342,-.013178,0.0*
1,1,.006,.010342,-.013178*
20,1,.006,.010342,-.013178,.008678,-.014842,0.0*
1,1,.006,.008678,-.014842*
20,1,.006,.008678,-.014842,.00675,-.016191,0.0*
1,1,.006,.00675,-.016191*
20,1,.006,.00675,-.016191,.004617,-.017186,0.0*
1,1,.006,.004617,-.017186*
20,1,.006,.004617,-.017186,.002344,-.017795,0.0*
1,1,.006,.002344,-.017795*
20,1,.006,.002344,-.017795,0.0,-.018,0.0*
1,1,.006,0.0,-.018*
20,1,.006,0.0,-.018,-.002344,-.017795,0.0*
1,1,.006,-.002344,-.017795*
20,1,.006,-.002344,-.017795,-.004617,-.017186,0.0*
1,1,.006,-.004617,-.017186*
20,1,.006,-.004617,-.017186,-.00675,-.016191,0.0*
1,1,.006,-.00675,-.016191*
20,1,.006,-.00675,-.016191,-.008678,-.014842,0.0*
1,1,.006,-.008678,-.014842*
20,1,.006,-.008678,-.014842,-.010342,-.013178,0.0*
1,1,.006,-.010342,-.013178*
20,1,.006,-.010342,-.013178,-.011691,-.01125,0.0*
1,1,.006,-.011691,-.01125*
20,1,.006,-.011691,-.01125,-.012686,-.009117,0.0*
1,1,.006,-.012686,-.009117*
20,1,.006,-.012686,-.009117,-.013295,-.006844,0.0*
1,1,.006,-.013295,-.006844*
20,1,.006,-.013295,-.006844,-.0135,-.0045,0.0*
1,1,.006,-.0135,-.0045*
20,1,.006,-.0135,-.0045,-.0135,.0045,0.0*
1,1,.006,-.0135,.0045*
1,1,.006,-.00383,-.00518*
20,1,.006,-.00383,-.00518,-.00225,-.0063,0.0*
1,1,.006,-.00225,-.0063*
20,1,.006,-.00225,-.0063,-.00045,-.00675,0.0*
1,1,.006,-.00045,-.00675*
20,1,.006,-.00045,-.00675,.00135,-.0063,0.0*
1,1,.006,.00135,-.0063*
20,1,.006,.00135,-.0063,.00292,-.00495,0.0*
1,1,.006,.00292,-.00495*
20,1,.006,.00292,-.00495,.00405,-.00292,0.0*
1,1,.006,.00405,-.00292*
20,1,.006,.00405,-.00292,.0045,-.0009,0.0*
1,1,.006,.0045,-.0009*
20,1,.006,.0045,-.0009,.0045,.00157,0.0*
1,1,.006,.0045,.00157*
20,1,.006,.0045,.00157,.00405,.0036,0.0*
1,1,.006,.00405,.0036*
20,1,.006,.00405,.0036,.00292,.0054,0.0*
1,1,.006,.00292,.0054*
20,1,.006,.00292,.0054,.00157,.0063,0.0*
1,1,.006,.00157,.0063*
20,1,.006,.00157,.0063,0.0,.00675,0.0*
1,1,.006,0.0,.00675*
20,1,.006,0.0,.00675,-.0018,.0063,0.0*
1,1,.006,-.0018,.0063*
20,1,.006,-.0018,.0063,-.00315,.0054,0.0*
1,1,.006,-.00315,.0054*
20,1,.006,-.00315,.0054,-.00405,.00405,0.0*
1,1,.006,-.00405,.00405*
20,1,.006,-.00405,.00405,-.0045,.00225,0.0*
1,1,.006,-.0045,.00225*
20,1,.006,-.0045,.00225,-.00405,.00068,0.0*
1,1,.006,-.00405,.00068*
20,1,.006,-.00405,.00068,-.00292,-.0009,0.0*
1,1,.006,-.00292,-.0009*
20,1,.006,-.00292,-.0009,-.00157,-.0018,0.0*
1,1,.006,-.00157,-.0018*
20,1,.006,-.00157,-.0018,0.0,-.00203,0.0*
1,1,.006,0.0,-.00203*
20,1,.006,0.0,-.00203,.0018,-.00158,0.0*
1,1,.006,.0018,-.00158*
20,1,.006,.0018,-.00158,.00315,-.00045,0.0*
1,1,.006,.00315,-.00045*
20,1,.006,.00315,-.00045,.0045,.00157,0.0*
1,1,.006,.0045,.00157*
%
%ADD16MACRO16*%
%AMMACRO32*
1,1,.006,-.004375,.013125*
20,1,.006,-.004375,.013125,.004375,.013125,0.0*
1,1,.006,.004375,.013125*
20,1,.006,.004375,.013125,.006654,.012926,0.0*
1,1,.006,.006654,.012926*
20,1,.006,.006654,.012926,.008864,.012333,0.0*
1,1,.006,.008864,.012333*
20,1,.006,.008864,.012333,.010937,.011367,0.0*
1,1,.006,.010937,.011367*
20,1,.006,.010937,.011367,.012812,.010054,0.0*
1,1,.006,.012812,.010054*
20,1,.006,.012812,.010054,.014429,.008437,0.0*
1,1,.006,.014429,.008437*
20,1,.006,.014429,.008437,.015742,.006563,0.0*
1,1,.006,.015742,.006563*
20,1,.006,.015742,.006563,.016708,.004489,0.0*
1,1,.006,.016708,.004489*
20,1,.006,.016708,.004489,.017301,.002279,0.0*
1,1,.006,.017301,.002279*
20,1,.006,.017301,.002279,.0175,0.0,0.0*
1,1,.006,.0175,0.0*
20,1,.006,.0175,0.0,.017301,-.002279,0.0*
1,1,.006,.017301,-.002279*
20,1,.006,.017301,-.002279,.016708,-.004489,0.0*
1,1,.006,.016708,-.004489*
20,1,.006,.016708,-.004489,.015742,-.006562,0.0*
1,1,.006,.015742,-.006562*
20,1,.006,.015742,-.006562,.014429,-.008437,0.0*
1,1,.006,.014429,-.008437*
20,1,.006,.014429,-.008437,.012812,-.010054,0.0*
1,1,.006,.012812,-.010054*
20,1,.006,.012812,-.010054,.010938,-.011367,0.0*
1,1,.006,.010938,-.011367*
20,1,.006,.010938,-.011367,.008864,-.012333,0.0*
1,1,.006,.008864,-.012333*
20,1,.006,.008864,-.012333,.006654,-.012926,0.0*
1,1,.006,.006654,-.012926*
20,1,.006,.006654,-.012926,.004375,-.013125,0.0*
1,1,.006,.004375,-.013125*
20,1,.006,.004375,-.013125,-.004375,-.013125,0.0*
1,1,.006,-.004375,-.013125*
20,1,.006,-.004375,-.013125,-.006654,-.012926,0.0*
1,1,.006,-.006654,-.012926*
20,1,.006,-.006654,-.012926,-.008864,-.012333,0.0*
1,1,.006,-.008864,-.012333*
20,1,.006,-.008864,-.012333,-.010937,-.011367,0.0*
1,1,.006,-.010937,-.011367*
20,1,.006,-.010937,-.011367,-.012812,-.010054,0.0*
1,1,.006,-.012812,-.010054*
20,1,.006,-.012812,-.010054,-.014429,-.008437,0.0*
1,1,.006,-.014429,-.008437*
20,1,.006,-.014429,-.008437,-.015742,-.006563,0.0*
1,1,.006,-.015742,-.006563*
20,1,.006,-.015742,-.006563,-.016708,-.004489,0.0*
1,1,.006,-.016708,-.004489*
20,1,.006,-.016708,-.004489,-.017301,-.002279,0.0*
1,1,.006,-.017301,-.002279*
20,1,.006,-.017301,-.002279,-.0175,0.0,0.0*
1,1,.006,-.0175,0.0*
20,1,.006,-.0175,0.0,-.017301,.002279,0.0*
1,1,.006,-.017301,.002279*
20,1,.006,-.017301,.002279,-.016708,.004489,0.0*
1,1,.006,-.016708,.004489*
20,1,.006,-.016708,.004489,-.015742,.006562,0.0*
1,1,.006,-.015742,.006562*
20,1,.006,-.015742,.006562,-.014429,.008437,0.0*
1,1,.006,-.014429,.008437*
20,1,.006,-.014429,.008437,-.012812,.010054,0.0*
1,1,.006,-.012812,.010054*
20,1,.006,-.012812,.010054,-.010938,.011367,0.0*
1,1,.006,-.010938,.011367*
20,1,.006,-.010938,.011367,-.008864,.012333,0.0*
1,1,.006,-.008864,.012333*
20,1,.006,-.008864,.012333,-.006654,.012926,0.0*
1,1,.006,-.006654,.012926*
20,1,.006,-.006654,.012926,-.004375,.013125,0.0*
1,1,.006,-.004375,.013125*
1,1,.006,0.0,-.00656*
20,1,.006,0.0,-.00656,.00153,-.00634,0.0*
1,1,.006,.00153,-.00634*
20,1,.006,.00153,-.00634,.00328,-.00569,0.0*
1,1,.006,.00328,-.00569*
20,1,.006,.00328,-.00569,.00437,-.00459,0.0*
1,1,.006,.00437,-.00459*
20,1,.006,.00437,-.00459,.00481,-.00306,0.0*
1,1,.006,.00481,-.00306*
20,1,.006,.00481,-.00306,.00437,-.00153,0.0*
1,1,.006,.00437,-.00153*
20,1,.006,.00437,-.00153,.00306,-.00022,0.0*
1,1,.006,.00306,-.00022*
20,1,.006,.00306,-.00022,.00109,.00044,0.0*
1,1,.006,.00109,.00044*
20,1,.006,.00109,.00044,-.00109,.00044,0.0*
1,1,.006,-.00109,.00044*
20,1,.006,-.00109,.00044,-.00241,.00087,0.0*
1,1,.006,-.00241,.00087*
20,1,.006,-.00241,.00087,-.0035,.00197,0.0*
1,1,.006,-.0035,.00197*
20,1,.006,-.0035,.00197,-.00394,.0035,0.0*
1,1,.006,-.00394,.0035*
20,1,.006,-.00394,.0035,-.00328,.00503,0.0*
1,1,.006,-.00328,.00503*
20,1,.006,-.00328,.00503,-.00175,.00612,0.0*
1,1,.006,-.00175,.00612*
20,1,.006,-.00175,.00612,0.0,.00656,0.0*
1,1,.006,0.0,.00656*
20,1,.006,0.0,.00656,.00175,.00612,0.0*
1,1,.006,.00175,.00612*
20,1,.006,.00175,.00612,.00328,.00503,0.0*
1,1,.006,.00328,.00503*
20,1,.006,.00328,.00503,.00394,.0035,0.0*
1,1,.006,.00394,.0035*
20,1,.006,.00394,.0035,.0035,.00197,0.0*
1,1,.006,.0035,.00197*
20,1,.006,.0035,.00197,.00241,.00087,0.0*
1,1,.006,.00241,.00087*
20,1,.006,.00241,.00087,.00109,.00044,0.0*
1,1,.006,.00109,.00044*
20,1,.006,.00109,.00044,-.00109,.00044,0.0*
1,1,.006,-.00109,.00044*
20,1,.006,-.00109,.00044,-.00306,-.00022,0.0*
1,1,.006,-.00306,-.00022*
20,1,.006,-.00306,-.00022,-.00437,-.00153,0.0*
1,1,.006,-.00437,-.00153*
20,1,.006,-.00437,-.00153,-.00481,-.00306,0.0*
1,1,.006,-.00481,-.00306*
20,1,.006,-.00481,-.00306,-.00437,-.00459,0.0*
1,1,.006,-.00437,-.00459*
20,1,.006,-.00437,-.00459,-.00328,-.00569,0.0*
1,1,.006,-.00328,-.00569*
20,1,.006,-.00328,-.00569,-.00153,-.00634,0.0*
1,1,.006,-.00153,-.00634*
20,1,.006,-.00153,-.00634,0.0,-.00656,0.0*
1,1,.006,0.0,-.00656*
%
%ADD32MACRO32*%
%AMMACRO20*
1,1,.006,.019,.01425*
20,1,.006,.019,.01425,.019,-.01425,0.0*
1,1,.006,.019,-.01425*
20,1,.006,.019,-.01425,-.019,-.01425,0.0*
1,1,.006,-.019,-.01425*
20,1,.006,-.019,-.01425,-.019,.01425,0.0*
1,1,.006,-.019,.01425*
20,1,.006,-.019,.01425,.019,.01425,0.0*
1,1,.006,.019,.01425*
1,1,.006,-.00713,-.00712*
20,1,.006,-.00713,-.00712,-.00713,.00713,0.0*
1,1,.006,-.00713,.00713*
20,1,.006,-.00713,.00713,-.00998,.00428,0.0*
1,1,.006,-.00998,.00428*
1,1,.006,-.00998,-.00712*
20,1,.006,-.00998,-.00712,-.00428,-.00712,0.0*
1,1,.006,-.00428,-.00712*
1,1,.006,.00713,.00713*
20,1,.006,.00713,.00713,.00523,.00666,0.0*
1,1,.006,.00523,.00666*
20,1,.006,.00523,.00666,.00381,.00547,0.0*
1,1,.006,.00381,.00547*
20,1,.006,.00381,.00547,.00286,.00404,0.0*
1,1,.006,.00286,.00404*
20,1,.006,.00286,.00404,.00215,.00214,0.0*
1,1,.006,.00215,.00214*
20,1,.006,.00215,.00214,.00191,0.0,0.0*
1,1,.006,.00191,0.0*
20,1,.006,.00191,0.0,.00215,-.00213,0.0*
1,1,.006,.00215,-.00213*
20,1,.006,.00215,-.00213,.00286,-.00403,0.0*
1,1,.006,.00286,-.00403*
20,1,.006,.00286,-.00403,.00381,-.00546,0.0*
1,1,.006,.00381,-.00546*
20,1,.006,.00381,-.00546,.00523,-.00665,0.0*
1,1,.006,.00523,-.00665*
20,1,.006,.00523,-.00665,.00713,-.00712,0.0*
1,1,.006,.00713,-.00712*
20,1,.006,.00713,-.00712,.00903,-.00665,0.0*
1,1,.006,.00903,-.00665*
20,1,.006,.00903,-.00665,.01046,-.00546,0.0*
1,1,.006,.01046,-.00546*
20,1,.006,.01046,-.00546,.01141,-.00403,0.0*
1,1,.006,.01141,-.00403*
20,1,.006,.01141,-.00403,.01212,-.00213,0.0*
1,1,.006,.01212,-.00213*
20,1,.006,.01212,-.00213,.01236,0.0,0.0*
1,1,.006,.01236,0.0*
20,1,.006,.01236,0.0,.01212,.00214,0.0*
1,1,.006,.01212,.00214*
20,1,.006,.01212,.00214,.01141,.00404,0.0*
1,1,.006,.01141,.00404*
20,1,.006,.01141,.00404,.01046,.00547,0.0*
1,1,.006,.01046,.00547*
20,1,.006,.01046,.00547,.00903,.00666,0.0*
1,1,.006,.00903,.00666*
20,1,.006,.00903,.00666,.00713,.00713,0.0*
1,1,.006,.00713,.00713*
%
%ADD20MACRO20*%
%ADD34C,.02*%
%ADD35C,.006*%
G75*
%LPD*%
G75*
G54D10*
X700Y19100D03*
X16200Y120100D03*
X27200Y821800D03*
X33800Y872600D03*
X1384200Y122800D03*
X1373200Y823500D03*
X1415100Y-36700D03*
X1389800Y879000D03*
X1708976Y265806D03*
G54D20*
X134251Y153543D03*
X161811D03*
X151968D03*
X144094D03*
X1708976Y631106D03*
G54D11*
X18577Y107902D03*
X5500Y119571D03*
Y139571D03*
Y159571D03*
X22000Y167200D03*
X5500Y179571D03*
Y199571D03*
X26500Y199500D03*
X21900Y199700D03*
X21800Y188100D03*
X5500Y219571D03*
Y239571D03*
X23100Y224500D03*
X27300Y229000D03*
X28400Y262800D03*
X18000Y271600D03*
X5500Y259571D03*
X26600Y249217D03*
Y253582D03*
X18000Y289400D03*
X28200Y296100D03*
X5500Y279571D03*
Y299571D03*
X24000Y308700D03*
X26300Y317600D03*
X21400Y327900D03*
Y341000D03*
X5500Y339571D03*
Y319571D03*
X24639Y321239D03*
X21400Y354000D03*
X22900Y365300D03*
X5500Y359571D03*
Y399571D03*
Y379571D03*
X31324Y410800D03*
X25350Y389000D03*
X17500Y412374D03*
X20713Y410087D03*
X5500Y419571D03*
Y439571D03*
X21300Y429500D03*
X20713Y418326D03*
X5500Y479571D03*
Y459571D03*
X23720Y472640D03*
X5500Y499571D03*
Y519571D03*
Y539571D03*
X29300Y539850D03*
X24800Y540900D03*
X5500Y579571D03*
Y559571D03*
Y599571D03*
Y639571D03*
Y619571D03*
Y679571D03*
Y659571D03*
X26100Y671200D03*
X24000Y659000D03*
X29500Y676500D03*
X5500Y699571D03*
X27125Y695275D03*
X25200Y712650D03*
X17500Y706300D03*
X21300Y728400D03*
X21108Y732713D03*
X18250Y749250D03*
X5500Y719571D03*
Y739571D03*
X25050Y716900D03*
X21250Y742650D03*
X27000Y754400D03*
X5500Y779571D03*
Y759571D03*
Y799571D03*
X10020Y835051D03*
X30020D03*
X5500Y819571D03*
X31400Y209190D03*
X46760Y209157D03*
X63250Y205050D03*
X42800Y200100D03*
X44400Y216600D03*
X34900Y216800D03*
X59800Y211800D03*
X50200Y212000D03*
X31500Y224400D03*
X41250Y216728D03*
X53400Y211928D03*
X38050Y216728D03*
X56600Y211928D03*
X58400Y271800D03*
X57500Y263300D03*
X63700Y257300D03*
X63800Y267100D03*
X44029Y272572D03*
X44426Y267408D03*
X35150Y273250D03*
X60872Y274328D03*
X63700Y260725D03*
X55800Y266293D03*
X63700Y263925D03*
X55800Y269493D03*
X44900Y261750D03*
X35300Y303100D03*
X59173Y288186D03*
X42900Y284500D03*
X58730Y299508D03*
X35150Y284350D03*
X47912Y294940D03*
X39000Y299500D03*
X53100Y279500D03*
X47800Y309400D03*
X31662Y303262D03*
X58700Y308600D03*
X61800Y306900D03*
X38800Y302900D03*
X62200Y288256D03*
X58383Y294947D03*
X47355Y303376D03*
X47991Y299958D03*
X49934Y280811D03*
X49100Y328300D03*
X39600Y317600D03*
X58990Y342700D03*
X34800Y321200D03*
X54600Y328600D03*
X38500Y321400D03*
X58100Y334600D03*
X62400Y334500D03*
X31700Y314700D03*
X52050Y316100D03*
X51050Y321650D03*
X62400Y342700D03*
X38518Y376916D03*
X34153D03*
X39866Y371366D03*
X52521Y350357D03*
X31500Y366900D03*
X48512Y356488D03*
X49300Y346700D03*
X43262Y357062D03*
X44866Y378634D03*
X55907Y350673D03*
X54200Y347400D03*
X63500Y353960D03*
X62838Y392392D03*
X60610Y381665D03*
X39300Y389557D03*
X47132Y444399D03*
X48000Y426000D03*
Y422500D03*
Y429500D03*
X57800Y420700D03*
X35709Y426942D03*
X43500Y418802D03*
X47734Y465792D03*
X45531Y474400D03*
X31500Y447000D03*
X64820Y455887D03*
X64680Y452389D03*
X64500Y459400D03*
X36750Y462900D03*
X53200Y462500D03*
X49812Y479921D03*
X33900Y469300D03*
X46500Y460300D03*
X46087Y455819D03*
X50140Y494559D03*
X60987Y489223D03*
X63519Y505320D03*
X62298Y484200D03*
X35700Y488500D03*
X60150Y506450D03*
X50140Y490750D03*
X60900Y495122D03*
X61870Y515670D03*
X60300Y533900D03*
X61128Y519646D03*
X64200Y534500D03*
X61800Y537000D03*
X55950Y564500D03*
Y572500D03*
X63000Y558930D03*
X62611Y608289D03*
X62400Y624500D03*
X53000Y645000D03*
X63300Y634800D03*
X43600Y665700D03*
X54200Y666800D03*
X60700Y682100D03*
X47800Y666400D03*
X35766Y673178D03*
X34500Y666500D03*
X39900Y678100D03*
X33600Y675800D03*
X43100Y670900D03*
X36624Y669155D03*
X47300Y704400D03*
X42300Y704900D03*
X62000Y713000D03*
X45800Y685100D03*
X42100Y684000D03*
X53500Y690200D03*
X60650Y694050D03*
X63300Y697200D03*
X59100Y705600D03*
X42130Y694440D03*
X38000Y684000D03*
X59300Y734900D03*
X54300Y729900D03*
X49300Y734900D03*
X54300Y739900D03*
Y734900D03*
X56590Y720410D03*
X47800Y772900D03*
X35000Y769900D03*
X39000D03*
X42800Y770000D03*
X52500Y779600D03*
X64900Y780500D03*
X50020Y835051D03*
X96584Y195100D03*
X78050Y196300D03*
X82676Y208785D03*
X67600Y209500D03*
X92859Y226659D03*
X87978Y226596D03*
X78508Y232693D03*
X72934Y232675D03*
X95200Y210800D03*
X85600D03*
X80600Y216700D03*
X71000Y216600D03*
X88276Y232700D03*
X88259Y223184D03*
X92659D03*
X78000Y229289D03*
X73600D03*
X77400Y216528D03*
X88800Y210851D03*
X74200Y216528D03*
X92000Y210851D03*
X97480Y266420D03*
X94600Y277100D03*
X93672Y270153D03*
X71870Y257120D03*
X77527Y255800D03*
X94530Y264671D03*
X75800Y274100D03*
X68100Y255000D03*
X71094Y285981D03*
X77964Y285670D03*
X68429Y288212D03*
X75400Y309700D03*
X71500Y297900D03*
X77100Y303800D03*
X65400D03*
X65500Y291900D03*
X77500D03*
X89400Y279300D03*
X96798Y301484D03*
Y297915D03*
X95700Y293900D03*
X73125Y288231D03*
X76325D03*
X65400Y288256D03*
X84600Y303000D03*
X78121Y325870D03*
X73721D03*
X70210Y342700D03*
X77290Y344212D03*
X86511Y344200D03*
X66400Y334500D03*
X66800Y342700D03*
X83500Y344200D03*
X80300D03*
X77421Y322470D03*
X74221D03*
X79455Y357174D03*
X75256Y370303D03*
X70591Y359309D03*
X71794Y377639D03*
X76055Y357145D03*
X82500Y362890D03*
X92580Y410761D03*
X79600Y399200D03*
X95223Y385704D03*
X79267Y410185D03*
X80940Y395989D03*
X86904Y385798D03*
X72708Y382055D03*
X68365Y381464D03*
X84700Y396000D03*
X92752Y434193D03*
X91370Y445394D03*
X70700Y443244D03*
X77859Y429879D03*
X72533Y416996D03*
X79164Y426221D03*
X96351Y443000D03*
Y438600D03*
X85042Y439144D03*
X91200Y448800D03*
Y453200D03*
X91311Y456609D03*
X89400Y470400D03*
X89500Y466600D03*
X85748Y475813D03*
X73232Y476912D03*
X97100Y466500D03*
X98400Y454400D03*
X77681Y499033D03*
X77413Y506468D03*
X76100Y483400D03*
X77700Y502500D03*
X88573Y503935D03*
X70910Y502219D03*
X67700Y499120D03*
X77700Y522500D03*
X88204Y543283D03*
X89200Y518700D03*
Y528500D03*
X65600Y543200D03*
X75600Y518600D03*
X67700Y518500D03*
X67162Y515142D03*
X77300Y531238D03*
X77700Y538500D03*
X74301Y538390D03*
X65800Y538900D03*
X74300Y533600D03*
X73900Y527050D03*
X77372Y526885D03*
X73700Y542600D03*
X70000Y542500D03*
X74000Y557000D03*
X77500Y554500D03*
X90500Y580100D03*
X81000Y579000D03*
X95252Y571638D03*
X70800Y559895D03*
X77400Y559000D03*
X77250Y562750D03*
X77400Y577000D03*
X71400Y578300D03*
X87555Y561085D03*
X87200Y574250D03*
X87337Y569268D03*
X84226Y577924D03*
X87200Y565785D03*
X77400Y550400D03*
X65381Y548719D03*
X87608Y557685D03*
X69100Y549200D03*
X73700Y549300D03*
X92000Y591200D03*
X69500Y586000D03*
X90500Y587000D03*
X80300Y596100D03*
X69258Y603000D03*
X82000Y592500D03*
X66000Y604800D03*
X88000Y613600D03*
X81000Y589000D03*
X78300Y634250D03*
X94860Y628750D03*
X78300Y637750D03*
X75800Y681900D03*
X94950Y677850D03*
X75450Y694150D03*
X69700Y690300D03*
X89825Y692875D03*
X79250Y716050D03*
X91800Y716100D03*
X66700Y713500D03*
X74500Y713400D03*
X91450Y707650D03*
X65350Y690356D03*
X89400Y749200D03*
X89300Y736300D03*
X95400Y731600D03*
Y728200D03*
X68900Y730000D03*
X68465Y736229D03*
X85800Y727500D03*
Y731000D03*
X74300Y769950D03*
X89800Y753400D03*
X69800Y772700D03*
X86900Y757900D03*
X89400Y762400D03*
X93100Y813200D03*
X70020Y835051D03*
X90020D03*
X93300Y818900D03*
X118577Y107902D03*
X104000Y128330D03*
X114364Y122054D03*
X118500Y176500D03*
Y173000D03*
X100900Y173800D03*
X108631Y168836D03*
X116000Y207000D03*
Y202000D03*
X118500Y188500D03*
X116000Y192000D03*
Y196500D03*
X118500Y185000D03*
Y181000D03*
X104100Y194600D03*
X103700Y200800D03*
X111967Y199632D03*
X119800Y234531D03*
X116000Y211500D03*
X103100Y211600D03*
X127330Y248029D03*
X112764Y264218D03*
X109600Y276850D03*
X112732Y272786D03*
X107340Y266140D03*
X101463Y268811D03*
X102499Y281183D03*
X109810Y310358D03*
X109972Y305968D03*
X112217Y296435D03*
X108500Y284000D03*
X107213Y301192D03*
X120700Y282400D03*
X100500Y285300D03*
X113915Y307600D03*
X117484D03*
X106400Y312200D03*
X101630Y312236D03*
X106717Y335600D03*
X117700Y323400D03*
X111900Y344200D03*
X113000Y336000D03*
X107558Y321012D03*
X122000Y343300D03*
X100277Y336077D03*
X102000Y364700D03*
X99128Y366961D03*
X108200Y378656D03*
X126800Y362500D03*
X108484Y348377D03*
X122645Y367966D03*
X117300Y361700D03*
X108453Y385164D03*
X100924Y409968D03*
X115951Y384138D03*
X111950Y392050D03*
X104204Y383661D03*
X129500Y412400D03*
X124290Y401910D03*
X125718Y383302D03*
X125600Y386700D03*
X107358Y409942D03*
X126122Y432323D03*
X105303Y419497D03*
X116173Y422379D03*
X107844Y414785D03*
X99749Y443671D03*
X99818Y437908D03*
X127925Y428093D03*
X116235Y444665D03*
X103179Y423267D03*
X103176Y434180D03*
X110406Y417067D03*
X113518Y420179D03*
X131304Y418855D03*
X131004Y422710D03*
X130633Y444763D03*
X120200Y436400D03*
X115500Y454700D03*
X111500D03*
X103500D03*
X120000Y451285D03*
X107900Y448900D03*
X101200Y470400D03*
X129520Y448660D03*
X127820Y452280D03*
X123696Y454452D03*
X114400Y550000D03*
X104461Y571715D03*
X100140Y559260D03*
X99460Y566200D03*
X102870Y565740D03*
Y561340D03*
X105851Y611436D03*
X104400Y590300D03*
X102000Y599000D03*
Y602500D03*
X101750Y595600D03*
X120351Y633500D03*
X126851Y633449D03*
X116551Y644936D03*
X128220Y620392D03*
X125581Y641436D03*
X109051Y645936D03*
X131051Y656436D03*
X119051Y653906D03*
X109800Y681900D03*
X130900Y714300D03*
Y710800D03*
X107950Y687650D03*
X124150Y707050D03*
X111400Y741800D03*
Y718300D03*
X118060Y743460D03*
X106900Y738600D03*
Y721300D03*
X115000Y717600D03*
X107000Y717800D03*
X132200Y761300D03*
Y756300D03*
X111300Y756000D03*
X109900Y828800D03*
X105400Y828700D03*
X103200Y825400D03*
X115500Y825500D03*
X107600D03*
X120000Y843500D03*
X126500Y878200D03*
Y871000D03*
X129000Y875000D03*
X117500Y878200D03*
X122000D03*
X124500Y875000D03*
X120000Y865000D03*
Y875000D03*
Y853500D03*
X138577Y107902D03*
X158577D03*
X149380Y176010D03*
X162500Y173500D03*
X163000Y211500D03*
X157200Y241400D03*
X153000Y225000D03*
X155026Y212580D03*
X134120Y267630D03*
X157300Y259900D03*
X157400Y254000D03*
X157300Y246500D03*
X155662Y266438D03*
X159662Y266600D03*
X162910Y244290D03*
X139286Y311214D03*
X166087Y304350D03*
X143000Y342900D03*
X155891Y339730D03*
X134800Y329600D03*
X144595Y312861D03*
X137862Y361723D03*
X161311Y371428D03*
X141216Y361163D03*
X145027D03*
X156573Y371799D03*
X140500Y390500D03*
X145500Y385500D03*
X158800Y406255D03*
X143000Y388000D03*
X142608Y403594D03*
X157550Y399100D03*
X146105Y403610D03*
X155657Y384291D03*
X137000Y436700D03*
X145901Y441262D03*
X139019Y443177D03*
X159540Y445692D03*
X146165Y444876D03*
X149838Y446190D03*
X150431Y420306D03*
X153100Y439000D03*
X136500Y417400D03*
X152978Y435602D03*
X137344Y446737D03*
X137000Y451300D03*
X163440Y453020D03*
X133000Y454700D03*
X143547Y477976D03*
X137000Y454700D03*
X159239Y449079D03*
X159082Y452509D03*
X165851Y630651D03*
X137551Y629849D03*
X149851Y631251D03*
X155851Y631051D03*
X160851Y630651D03*
X150069Y640500D03*
X150280Y636620D03*
X150600Y648300D03*
X150409Y643884D03*
X153019Y622720D03*
X159716Y620392D03*
X166015D03*
X136651Y653036D03*
X162100Y677800D03*
X164400Y668300D03*
X160500Y689500D03*
X150000Y701500D03*
X142500Y709000D03*
X137000Y715500D03*
X164500Y693500D03*
X144400Y731600D03*
Y728200D03*
X136400Y738300D03*
Y721800D03*
X161200Y723900D03*
X150200Y729400D03*
X153700D03*
X157700Y748900D03*
X150450Y744150D03*
X146450Y736150D03*
X135700Y745200D03*
X163800Y771000D03*
X160400D03*
X154000Y779000D03*
X160700Y753400D03*
X143000Y784500D03*
X146500D03*
X150500Y804000D03*
X139250Y791250D03*
X143250Y799250D03*
X153500Y808500D03*
X163800Y820000D03*
X160400D03*
X138500Y835000D03*
X137600Y839500D03*
X141100Y824500D03*
X141000Y830700D03*
X145900Y824400D03*
X142500Y862500D03*
Y867500D03*
Y872500D03*
X138500Y869500D03*
Y875200D03*
X141000Y877700D03*
X145500D03*
X149700D03*
X142500Y856500D03*
X159449Y878276D03*
X178577Y107902D03*
X181738Y122711D03*
X171500Y207500D03*
Y202500D03*
X193400Y192900D03*
X191800Y189600D03*
X196018Y204200D03*
X167000Y211500D03*
X172450Y211050D03*
X183400Y221600D03*
X171100Y247500D03*
X191000Y246500D03*
X167600Y247600D03*
X193303Y264310D03*
X167700Y296882D03*
Y292517D03*
X180850Y285650D03*
X170062Y304556D03*
X174943Y321015D03*
X167687Y329434D03*
X192407Y320262D03*
X180571Y327023D03*
X176674Y344934D03*
X189365Y329905D03*
X179381Y369903D03*
X196529Y352284D03*
X185970Y358962D03*
X195940Y348814D03*
X182969Y352641D03*
X192150Y406429D03*
X197000Y404000D03*
X171434Y398093D03*
X177550Y407850D03*
X166321Y388316D03*
X176098Y444355D03*
X197850Y437450D03*
X185000Y419900D03*
X197531Y451187D03*
X189381Y451394D03*
X193718D03*
X196239Y462262D03*
X173471Y454700D03*
X175912Y450747D03*
X166534Y450821D03*
X186675Y453505D03*
X177500Y454300D03*
X199900Y544500D03*
X196782Y563564D03*
X197334Y567232D03*
X197500Y577300D03*
X189500Y567700D03*
X185500Y577300D03*
X184189Y564504D03*
X185500Y567700D03*
X193001Y574708D03*
X181000Y585000D03*
Y581500D03*
X198600Y599750D03*
Y588750D03*
X181371Y601636D03*
X181000Y595200D03*
X168769Y622720D03*
X171300Y678300D03*
X175200Y678500D03*
X199900Y692000D03*
X171000Y715900D03*
X167600D03*
X193500Y700000D03*
X182500Y705500D03*
X186000D03*
X178750Y712250D03*
X189000Y684500D03*
X185000D03*
X167000Y686500D03*
X199900Y747500D03*
Y741000D03*
X190000Y725000D03*
X177700Y723900D03*
X182860Y742240D03*
X181200Y748900D03*
X184700Y729400D03*
X182750Y720250D03*
X193000Y729500D03*
X171000Y764900D03*
X167600D03*
X190000Y780500D03*
X170500Y779000D03*
X193500Y755500D03*
X182500Y761000D03*
X186000D03*
X182750Y775750D03*
X178000Y753400D03*
X178750Y767750D03*
X199900Y796500D03*
X175660Y797340D03*
X174000Y804000D03*
X177500Y784500D03*
X170800Y808500D03*
X193000Y785000D03*
X195000Y824090D03*
X188572Y832186D03*
X196474Y832178D03*
X197420Y821701D03*
X194120Y830301D03*
X190920D03*
X176900Y867600D03*
X173500D03*
X196000Y868700D03*
X176771Y878276D03*
X195669D03*
X168898Y878200D03*
X185500D03*
X197218Y871676D03*
X227669Y5500D03*
X210028Y12605D03*
Y32605D03*
Y52605D03*
Y72605D03*
X226533Y72591D03*
X228121Y63589D03*
X228163Y68589D03*
X210028Y92605D03*
X227989Y83589D03*
X222354Y103006D03*
X228163Y78589D03*
X227606Y98642D03*
X223641Y99302D03*
X228163Y93589D03*
Y88589D03*
X228500Y138100D03*
X223750Y141370D03*
X218725Y138175D03*
X228007Y123787D03*
X233500Y137000D03*
X220300Y129300D03*
X222356Y133438D03*
X228708Y127115D03*
X215136Y142786D03*
X218299Y123319D03*
X224576Y116678D03*
X221418Y109634D03*
X210478Y151203D03*
X233537Y160630D03*
X213282Y188452D03*
X202892Y188441D03*
X205013Y192596D03*
X210484Y179525D03*
X206297Y188492D03*
X209866D03*
X214794Y212100D03*
X206200Y247500D03*
X209200Y252800D03*
X230400Y283400D03*
X222200Y300500D03*
X205840Y325381D03*
X210177D03*
X218102Y334880D03*
X218070Y340244D03*
X221460Y335475D03*
Y339875D03*
X228100Y364600D03*
X219018Y378000D03*
X223383D03*
X217000Y360000D03*
X219580Y356970D03*
X214776Y352807D03*
X212536Y349805D03*
X205750Y408250D03*
X205915Y422424D03*
X217190Y428485D03*
X212200Y428800D03*
X212000Y438713D03*
X217500Y441992D03*
X205200Y442900D03*
X220897Y441833D03*
X220800Y446000D03*
X200100Y415100D03*
X201868Y451187D03*
X227700Y476537D03*
Y472200D03*
X216404Y469751D03*
X216282Y463288D03*
X219763Y472187D03*
X230572Y455128D03*
X228900Y446800D03*
X219300Y508700D03*
X228298Y488100D03*
X228347Y484700D03*
X219700Y489800D03*
X202700Y495400D03*
X206700Y498000D03*
X216600Y496550D03*
X217800Y512500D03*
X200917Y490578D03*
X203550Y484522D03*
X233290Y493277D03*
X206700Y494000D03*
X203500Y499200D03*
X207026Y483956D03*
X219800Y493700D03*
X218906Y483186D03*
X226300Y505700D03*
X226530Y502307D03*
X216873Y516458D03*
X203300Y538500D03*
X206700Y544500D03*
Y538500D03*
X221000Y541300D03*
X217500Y519800D03*
Y529250D03*
X225000Y541300D03*
X229200Y514800D03*
X216300Y546350D03*
X203300Y544500D03*
Y548500D03*
X219700Y550500D03*
X218780Y560082D03*
X206700Y548500D03*
X216300Y550500D03*
X216278Y567341D03*
X202300Y559763D03*
X222300Y577300D03*
X216563Y555908D03*
X229800Y558500D03*
X206700Y554500D03*
X203304Y554684D03*
X205700Y559763D03*
X222500Y573220D03*
X216241Y563095D03*
X216090Y593937D03*
X227500Y603500D03*
X201000Y674000D03*
X206952Y655370D03*
X203300Y692000D03*
X219000Y694000D03*
X210000Y700000D03*
X231500Y699000D03*
X217000Y705500D03*
X203300Y747500D03*
Y741000D03*
X213500Y725000D03*
X215160Y718340D03*
X210300Y729500D03*
X227409Y775903D03*
X233000D03*
X213500Y780500D03*
X210000Y755500D03*
X215160Y773840D03*
X217000Y761000D03*
X228550Y772700D03*
X231750D03*
X203300Y796500D03*
X210300Y785000D03*
X203124Y824090D03*
X233650Y827374D03*
X208700Y828000D03*
X201641Y827947D03*
X214380Y827374D03*
X221052D03*
X226978D03*
X200620Y821701D03*
X231915Y830301D03*
X219317D03*
X206718D03*
X228715D03*
X216117D03*
X203518D03*
X201500Y868700D03*
X233464Y878276D03*
X208267D03*
X201969D03*
X220866D03*
X214567D03*
X227166D03*
X225615Y875176D03*
X213017D03*
X200418Y871676D03*
X222415Y875176D03*
X209817D03*
X247669Y5500D03*
X258159Y73589D03*
X257851Y63589D03*
X257759Y68589D03*
X257769Y83589D03*
X264817Y105350D03*
X257731Y78589D03*
X258100Y93589D03*
X257912Y101408D03*
X258029Y97353D03*
X260562Y85988D03*
X254000Y131500D03*
X264500Y142750D03*
X254500D03*
X246500Y139000D03*
X243000D03*
X258068Y110180D03*
X259331Y118580D03*
X264443Y109587D03*
X257422Y121792D03*
X259500Y143250D03*
Y147750D03*
Y160750D03*
Y156250D03*
X264397Y160977D03*
X264500Y157250D03*
Y153750D03*
Y150250D03*
Y146250D03*
X259500Y152000D03*
X254500Y161250D03*
Y157250D03*
Y153750D03*
Y150250D03*
Y146250D03*
X239600Y142900D03*
X243618Y143381D03*
X243500Y147500D03*
X241231Y238869D03*
X236300Y227280D03*
X247500Y233750D03*
X244300Y226700D03*
X266500Y239400D03*
X245400Y296500D03*
X267300Y300600D03*
Y328640D03*
X257340Y338640D03*
X248160Y343140D03*
X267300Y362200D03*
X244000Y377617D03*
X260929Y345571D03*
X248930Y358000D03*
X244000Y381982D03*
X258500Y391200D03*
X239100Y399200D03*
X251700Y421600D03*
Y425200D03*
X238400Y416200D03*
X235750Y419500D03*
X262900Y438700D03*
X246375Y440725D03*
X265100Y443300D03*
X264100Y425400D03*
X249342Y439064D03*
X251800Y470100D03*
X248500Y465000D03*
X263700Y474600D03*
X257493Y456679D03*
X253302D03*
X257400Y477300D03*
X235850Y455050D03*
X246300Y478600D03*
Y485400D03*
X246407Y488799D03*
X256300Y494500D03*
X244100Y499900D03*
X246800Y496800D03*
X257400Y481637D03*
X256300Y486000D03*
Y490000D03*
X260646Y499181D03*
X256855Y499154D03*
X265019Y497483D03*
X255487Y512454D03*
X242800Y495486D03*
X246500Y493400D03*
X240450Y499400D03*
X236737Y493170D03*
X243200Y508000D03*
X250200Y506600D03*
X264522Y511690D03*
X260407Y502674D03*
X257207D03*
X246300Y482000D03*
X239139Y525077D03*
X239321Y521081D03*
X249700Y525737D03*
Y521250D03*
X264500Y521309D03*
X261100Y521250D03*
X250100Y537100D03*
X236100Y517100D03*
X263300Y526300D03*
X234777Y550569D03*
X252238Y574238D03*
X255738D03*
X253500Y590500D03*
X257413D03*
X266100Y614400D03*
X265850Y606400D03*
X248500Y583000D03*
X260100Y647400D03*
X259300Y632400D03*
Y639300D03*
X250500Y642500D03*
X265900Y622400D03*
X238100Y643400D03*
X247717Y633233D03*
X259300Y635900D03*
X236000Y656000D03*
X256600Y652200D03*
X241000Y712500D03*
X262628Y744470D03*
X266980Y723854D03*
X241000Y721500D03*
X258100Y726100D03*
X241000Y725500D03*
Y718000D03*
X266906Y775531D03*
X263181Y772181D03*
X249025Y827374D03*
X255697D03*
X261624D03*
X266561Y830301D03*
X253962D03*
X263361D03*
X250762D03*
X261811Y878276D03*
X249212D03*
X239764D03*
X255511D03*
X260261Y875176D03*
X238213D03*
X257061D03*
X235013D03*
X267669Y5500D03*
X290000Y141100D03*
X274250Y133750D03*
X292000Y130000D03*
X285500D03*
X284440Y139580D03*
X285250Y133750D03*
X294500Y152500D03*
X286000Y143800D03*
X286100Y153900D03*
X280000D03*
X290500Y152500D03*
X275000Y147500D03*
X277800Y208500D03*
X271231Y237031D03*
X283622Y226340D03*
X279257D03*
X269849Y308414D03*
X277300Y304800D03*
X297090Y311350D03*
X282700Y300100D03*
X299600Y297662D03*
X269270Y315759D03*
X287200Y326802D03*
X287800Y311600D03*
X267979Y342500D03*
X295400Y325390D03*
X283700Y322100D03*
X297729Y362571D03*
X288270Y365240D03*
X297729Y351029D03*
X294009Y363063D03*
X293800Y436100D03*
X301170Y462780D03*
X301162Y459290D03*
X273783Y476100D03*
X283400Y477900D03*
X284200Y465000D03*
X275900Y467300D03*
X285800Y460810D03*
X290838Y501600D03*
X286181Y498546D03*
X291500Y497700D03*
X269000Y504962D03*
X275286Y504392D03*
X280749Y512744D03*
X286169Y502000D03*
X285776Y489300D03*
X272860Y489147D03*
X282400Y487300D03*
X295876Y520800D03*
X296200Y566900D03*
X290000Y578165D03*
X300835D03*
X279994Y554794D03*
X283600Y551400D03*
X291000Y561450D03*
X280200Y551400D03*
X289835Y583165D03*
Y588165D03*
X269000Y589000D03*
X269335Y593165D03*
X300835Y583165D03*
X301000Y588665D03*
X288835Y593165D03*
X297750Y592750D03*
X276300Y617350D03*
X281700Y634900D03*
X281800Y638900D03*
X288400Y626100D03*
Y634200D03*
X292500Y630200D03*
X271500Y639500D03*
X281100Y651700D03*
X285500Y704900D03*
X298406Y706000D03*
X290338Y715800D03*
X278406Y716531D03*
X274406Y716598D03*
X270000Y732650D03*
X283161Y730092D03*
X281500Y748500D03*
X275609Y726886D03*
X270556Y716702D03*
X269500Y736150D03*
X286500Y740500D03*
X287278Y729031D03*
X286406Y716531D03*
X296132Y726171D03*
X290720Y726333D03*
X285333Y726241D03*
X282406Y716598D03*
X298620Y728596D03*
X282378Y775431D03*
X298500Y752000D03*
X272116Y755592D03*
X298400Y775700D03*
X283500Y765631D03*
X268193Y755633D03*
X293692Y765571D03*
X287115Y765584D03*
X281500Y752000D03*
X299184Y765691D03*
X268296Y827374D03*
X280894D03*
X274222D03*
X279159Y830301D03*
X275959D03*
X286800Y863300D03*
X280800Y863500D03*
X268110Y878276D03*
X280708D03*
X287008D03*
X274410D03*
X285500Y866200D03*
X272859Y875176D03*
X282300Y866200D03*
X269659Y875176D03*
X307300Y221702D03*
X307834Y237966D03*
X306900Y251000D03*
X302500Y251600D03*
X311882Y310550D03*
X306800Y290500D03*
X328842Y300042D03*
X307425Y309838D03*
X303517Y309777D03*
X312900Y290450D03*
X321300Y301500D03*
X334200Y299600D03*
X313200Y299900D03*
X331800Y309100D03*
X310485Y314670D03*
X328800Y315900D03*
X316420Y331830D03*
X302749Y332651D03*
X326041Y329282D03*
Y325000D03*
X310839Y344339D03*
X315300Y344500D03*
X315900Y320900D03*
X313100Y371038D03*
Y374438D03*
X301320Y362500D03*
X313875Y364201D03*
X310475Y364193D03*
X316315Y369889D03*
X316205Y376006D03*
X301929Y351100D03*
X313500Y437400D03*
Y441000D03*
X313300Y429603D03*
X313294Y434006D03*
X302140Y444160D03*
X306521Y463576D03*
X304293Y466146D03*
X329014Y472022D03*
X306612Y460177D03*
X307400Y467600D03*
X303440Y475360D03*
X322268Y466591D03*
X322305Y469991D03*
X321900Y459800D03*
X322036Y463198D03*
X327512Y509612D03*
X303800Y505100D03*
X304400Y511400D03*
X327589Y504300D03*
X333102Y485902D03*
X330000Y501900D03*
X303500Y491000D03*
X305500Y483550D03*
X320500Y531000D03*
X321000Y527000D03*
X322700Y536500D03*
X311406Y535944D03*
X306900Y529100D03*
X311500Y548000D03*
X314900D03*
X322100Y638500D03*
X309000Y679000D03*
X305500Y676400D03*
X334800Y712000D03*
X302406Y706031D03*
X306406D03*
X322178Y729178D03*
X310016Y729793D03*
X312500Y716500D03*
X317300Y739300D03*
X302000Y740800D03*
X320000Y718200D03*
X323600Y717800D03*
X301310Y726403D03*
X326000Y729000D03*
X315132Y727197D03*
X307278Y726198D03*
X313452Y753856D03*
X330000Y754000D03*
X311200Y765500D03*
X311406Y775198D03*
X302700Y765400D03*
X315406Y765598D03*
Y775200D03*
X307406Y775198D03*
X312017Y827374D03*
X318689D03*
X324616D03*
X331288D03*
X329553Y830301D03*
X316954D03*
X326353D03*
X313754D03*
X306500Y868700D03*
X312000Y868600D03*
X324803Y878276D03*
X331102D03*
X318503D03*
X312500Y878200D03*
X323253Y875176D03*
X310955Y865676D03*
X332651Y875176D03*
X320053D03*
X307755Y865676D03*
X362528Y123931D03*
X358917Y124122D03*
X355069D03*
X352600Y128200D03*
Y132537D03*
X337000Y162000D03*
X354800Y171400D03*
X358300D03*
X354800Y166900D03*
X358300D03*
X354800Y162400D03*
X358300D03*
X362300D03*
Y166900D03*
Y171400D03*
X354800Y181900D03*
X358300D03*
X354800Y176900D03*
X358300D03*
X362300D03*
Y181900D03*
X345820Y256570D03*
X349970Y256720D03*
X344958Y300740D03*
X344955Y305843D03*
X341652Y305034D03*
Y301534D03*
X362500Y341700D03*
X362825Y336000D03*
X359132Y326647D03*
X351515Y327915D03*
X356953Y353653D03*
X359403Y351203D03*
X352003Y358603D03*
X354505Y356102D03*
X360820Y359299D03*
X363270Y356940D03*
X355872Y363965D03*
X358362Y361649D03*
X359500Y448800D03*
X335570Y491460D03*
X342300Y511600D03*
X350000Y537600D03*
X347100Y605300D03*
X357600Y638300D03*
X367000Y704000D03*
X360000D03*
X344200Y696300D03*
X354300Y696000D03*
Y704500D03*
X363500Y704000D03*
X366792Y734171D03*
X364275Y723033D03*
X359500Y727335D03*
X342900Y727200D03*
X364354Y731801D03*
X362091Y729538D03*
X367675Y723000D03*
X349813Y827374D03*
X356485D03*
X362411D03*
X343886D03*
X337214D03*
X367348Y830301D03*
X354750D03*
X342151D03*
X364148D03*
X351550D03*
X338951D03*
X362599Y878276D03*
X356299D03*
X350000D03*
X343700D03*
X337402D03*
X361048Y875176D03*
X348450D03*
X335851D03*
X357848D03*
X345250D03*
X387669Y5500D03*
X401300Y159800D03*
X401200Y150200D03*
X401300Y156715D03*
Y153215D03*
X400400Y189100D03*
X383600Y203200D03*
X376600Y261350D03*
X381700Y265800D03*
X368900Y315700D03*
X370700Y353900D03*
X395100Y449100D03*
X380300Y508700D03*
X401000Y575500D03*
X372000Y579300D03*
X388900Y550400D03*
X386500Y607900D03*
X370500Y705500D03*
X374275Y722919D03*
X370875Y723000D03*
X369083Y827374D03*
X384459D03*
X391131D03*
X397057D03*
X401994Y830301D03*
X389396D03*
X398794D03*
X386196D03*
X378346Y878276D03*
X390944D03*
X397244D03*
X384646D03*
X370500Y878200D03*
X395694Y875176D03*
X383096D03*
X392494D03*
X379896D03*
X407669Y5500D03*
X427669D03*
X406500Y141700D03*
X403600Y142542D03*
X433000Y169700D03*
X406500Y146900D03*
X435161Y166892D03*
X403600Y146042D03*
X422876Y199830D03*
Y204195D03*
X421757Y177999D03*
X411400Y183900D03*
X433400Y176800D03*
X410900Y217100D03*
X404170Y326708D03*
X403900Y315492D03*
X404040Y318900D03*
Y323300D03*
X416100Y470800D03*
X418900Y529300D03*
X410300Y637500D03*
X416328Y827374D03*
X428926D03*
X422254D03*
X403729D03*
X409656D03*
X427191Y830301D03*
X414593D03*
X423991D03*
X411393D03*
X416141Y878276D03*
X431889D03*
X422441D03*
X403543D03*
X409843D03*
X420891Y875176D03*
X408292D03*
X417691D03*
X405092D03*
X447669Y5500D03*
X467669D03*
X461900Y62300D03*
X466000D03*
X457700D03*
X465127Y57727D03*
X452600Y114254D03*
X454871Y122291D03*
X457400Y138900D03*
X454926Y118791D03*
X455800Y110200D03*
X452500Y153300D03*
X438561Y166892D03*
X456500Y169783D03*
Y165418D03*
X455800Y208300D03*
X464086Y287614D03*
X461389Y318510D03*
X464086Y340500D03*
X459200Y369300D03*
X462700D03*
X455450Y376050D03*
X466700Y388800D03*
X469700Y393300D03*
X459450Y384050D03*
X448200Y531400D03*
X443000Y596500D03*
X469000Y784000D03*
X461300Y813100D03*
X457900D03*
X456335Y835051D03*
X444500Y864450D03*
X438189Y878276D03*
X489261Y-14185D03*
X470200Y62300D03*
X478400D03*
X474400D03*
X483250Y59480D03*
X479700Y90100D03*
X491466Y126683D03*
X496782Y134315D03*
X474990Y122660D03*
X494800Y162900D03*
X480910Y164099D03*
X480800Y160700D03*
X498900Y171800D03*
X498000Y194200D03*
X493186Y272414D03*
X501867Y295490D03*
X477037Y333841D03*
X473637Y333876D03*
X500198Y324041D03*
X480532Y321332D03*
X480000Y355800D03*
X476600D03*
X486700Y363800D03*
X470200D03*
X493700Y369300D03*
X490200Y388800D03*
X491860Y382140D03*
X487000Y393300D03*
X480368Y405606D03*
X476531D03*
X472600Y477700D03*
X487400Y492100D03*
X500800Y567200D03*
X487906Y768598D03*
X491906Y768531D03*
X496061Y781678D03*
X482925Y777422D03*
X489522Y780127D03*
X478000Y777500D03*
X483850Y773800D03*
X500778Y781031D03*
X499906Y768531D03*
X497910Y778824D03*
X495906Y768598D03*
X494582Y800500D03*
X483500Y784650D03*
X485300Y808250D03*
X480100Y784575D03*
X497000Y817500D03*
X483000Y788150D03*
X499000Y793000D03*
X485300Y811750D03*
X500415Y817532D03*
X494582Y804000D03*
X496335Y835051D03*
X480406Y827531D03*
X495878Y827431D03*
X477206Y820648D03*
X500700Y828100D03*
X500807Y831499D03*
X491906Y827403D03*
X487906D03*
X530400Y72400D03*
X524000Y43500D03*
X532500Y62900D03*
X536100Y56700D03*
X531400Y102900D03*
X522700D03*
X528700Y91100D03*
X531200Y87900D03*
X535400Y87400D03*
X532900Y92400D03*
X532400Y78200D03*
X509369Y141559D03*
X530800Y123900D03*
X521465Y140964D03*
X513876D03*
X532110Y138400D03*
X525000D03*
X506006Y126183D03*
X507861Y134154D03*
X519300Y138871D03*
X530177Y140708D03*
X516100Y138871D03*
X526977Y140708D03*
X529176Y151713D03*
X532560Y152046D03*
X534000Y167400D03*
X535960Y151999D03*
X507300Y175500D03*
X515348Y163101D03*
X515354Y168998D03*
X505100Y164800D03*
X503975Y172372D03*
X518686Y163800D03*
Y168200D03*
X512600Y186500D03*
X517599Y229658D03*
X531232Y229927D03*
X534481Y243676D03*
X510462Y261315D03*
X525881Y287776D03*
X534481Y286876D03*
X518277Y288680D03*
X532921Y298436D03*
X509143Y284391D03*
X529881Y287376D03*
X525347Y336979D03*
X512100Y319700D03*
X532499Y315591D03*
X533779Y336979D03*
X507809Y336341D03*
X522209Y333841D03*
X522409Y318441D03*
X529126Y342336D03*
X532978Y371023D03*
X534500Y395100D03*
X528850Y394750D03*
X518100Y453200D03*
X520500Y519400D03*
X527700Y587500D03*
X522500Y782031D03*
X535178Y781000D03*
X511800Y768300D03*
X515900D03*
X531500Y774500D03*
X531600Y770200D03*
X515278Y779198D03*
X519748Y768297D03*
X507729Y778198D03*
X504278Y779198D03*
X507906Y768531D03*
X528179Y782555D03*
X524795Y778529D03*
X511484Y778515D03*
X515650Y764500D03*
X503906Y768598D03*
X519906Y764900D03*
X526274Y806000D03*
X511500Y803000D03*
X532000Y792500D03*
X515000D03*
X524700Y817500D03*
X507044Y817569D03*
X516943Y817401D03*
X528906Y817598D03*
X512716Y817550D03*
X533800Y835500D03*
X508579Y827421D03*
X527500Y836200D03*
X512679Y827500D03*
X527941Y864680D03*
X541200Y73400D03*
X541600Y62600D03*
X544500Y57400D03*
X546800Y46300D03*
X566700Y48700D03*
X570900Y56200D03*
X537400Y91000D03*
X540100Y102900D03*
X541700Y92300D03*
X544600Y87300D03*
X538800Y76900D03*
X546800Y76200D03*
X566100Y103100D03*
X543000Y76300D03*
X539031Y136200D03*
X547400Y136170D03*
X560633Y127988D03*
X552800Y140800D03*
X562603Y140881D03*
X544800Y137769D03*
X541600D03*
X549100Y126900D03*
X566531Y143123D03*
X570754Y147365D03*
X546800Y163450D03*
X564483Y167935D03*
X558121Y167249D03*
X543900Y154800D03*
X550300D03*
X548700Y152200D03*
X545500D03*
X547173Y167987D03*
X561567Y205767D03*
X554149Y200229D03*
X541446Y222562D03*
X569500Y240225D03*
X546494Y216010D03*
X539798Y228856D03*
X539934Y232660D03*
X540035Y236294D03*
X541637Y263240D03*
X545974D03*
X541681Y297976D03*
X539481Y286676D03*
X544993Y281352D03*
X539450Y322166D03*
X539507Y330787D03*
X554400Y335900D03*
X539400Y376444D03*
X560531Y358080D03*
X564100Y358100D03*
X556500Y358000D03*
X561781Y346281D03*
X561300Y369500D03*
X552720Y364180D03*
X539400Y380781D03*
X550000Y381000D03*
X559973Y387638D03*
X561912Y390762D03*
X567150Y415750D03*
X560900Y413700D03*
X544000Y761000D03*
X540500Y781000D03*
X547395Y761198D03*
X540500Y761000D03*
X542500Y806000D03*
X550186Y827374D03*
X543514D03*
X568711D03*
X556113D03*
X562785D03*
X561050Y830301D03*
X548451D03*
X570448D03*
X557850D03*
X545251D03*
X538000Y878200D03*
X550000Y878276D03*
X562598D03*
X568898D03*
X556300D03*
X544000Y878200D03*
X567348Y875176D03*
X554750D03*
X542151D03*
X564148D03*
X551550D03*
X538951D03*
X590000Y46200D03*
X579900Y55800D03*
X588000Y57200D03*
X584600Y63200D03*
X575800Y63100D03*
X588000Y72200D03*
X579000Y72300D03*
X573800Y72400D03*
X576800Y91600D03*
X584600Y78200D03*
X575500Y78500D03*
X588000Y87100D03*
X579000Y87200D03*
X584500Y93200D03*
X580700Y90900D03*
X572500Y91200D03*
X576300Y103300D03*
X585100D03*
X580800Y76000D03*
X574100Y87800D03*
X579200Y140400D03*
X583640Y140636D03*
X598240Y137800D03*
X572990Y140501D03*
X588955Y140600D03*
X591377Y125797D03*
X597846Y125623D03*
X577650Y137780D03*
X587850Y137800D03*
X604450Y137780D03*
X574450D03*
X584650Y137800D03*
X601250Y137780D03*
X593000Y152800D03*
X598300Y152850D03*
X597350Y149950D03*
X594150D03*
X596253Y210000D03*
X603000Y190710D03*
X579811Y179500D03*
X582400Y209500D03*
X597813Y220858D03*
X597763Y242608D03*
X602763Y240858D03*
X597763Y231608D03*
Y235108D03*
Y239108D03*
X602763Y236608D03*
Y232108D03*
X587100Y234800D03*
X587438Y230850D03*
X576100Y234500D03*
X592563Y228308D03*
X588963Y227408D03*
X587400Y238200D03*
X597763Y246108D03*
Y250108D03*
X602763Y245108D03*
Y249608D03*
X604170Y337900D03*
X600800Y337400D03*
X597600Y339100D03*
X599100Y348700D03*
X597500Y352050D03*
X589500Y361000D03*
X581700Y360700D03*
X573900Y360600D03*
X603500Y371200D03*
X576800Y369200D03*
X604400Y421200D03*
X579900Y427400D03*
X584500Y462500D03*
X600400Y538000D03*
X586900Y713200D03*
X593908Y827374D03*
X600580D03*
X587981D03*
X581309D03*
X575383D03*
X598845Y830301D03*
X586246D03*
X573648D03*
X595645D03*
X583046D03*
X594095Y878276D03*
X600393D03*
X587795D03*
X575197D03*
X581497D03*
X592545Y875176D03*
X579947D03*
X601944D03*
X589345D03*
X576747D03*
X631100Y72300D03*
X622100Y72400D03*
X628200Y62600D03*
X619200Y62800D03*
X614300Y55800D03*
X620838Y58628D03*
X634100Y46800D03*
X631300Y57100D03*
X616800Y72200D03*
X624700Y61400D03*
X611100Y103300D03*
X619600D03*
X628300D03*
X615800Y91200D03*
X624400Y91100D03*
X628000Y93000D03*
X618300Y88000D03*
X628100Y77700D03*
X619400Y77500D03*
X631200Y87200D03*
X624000Y76000D03*
X621900Y87600D03*
X619700Y92100D03*
X614721Y138287D03*
X623498Y140671D03*
X629393Y140451D03*
X631940Y137800D03*
X607520Y137780D03*
X605924Y126398D03*
X608089Y131519D03*
X627826Y137880D03*
X638150D03*
X624626D03*
X634950D03*
X617000Y144500D03*
X633900Y149600D03*
X636950Y149650D03*
X635482Y207733D03*
X607700Y211800D03*
X608800Y221400D03*
X635863Y216308D03*
X607763Y242608D03*
Y231608D03*
Y235108D03*
Y239108D03*
X619363Y225108D03*
X623363D03*
X635190Y219641D03*
X631063Y242108D03*
X616970Y235017D03*
X629663Y221708D03*
X616718Y238408D03*
X627363Y224358D03*
X637300Y234500D03*
X607763Y246108D03*
Y250108D03*
X628563Y249108D03*
X624101Y330010D03*
X627500Y329900D03*
X635350Y320850D03*
X622629Y344635D03*
X616640Y342230D03*
X620000Y341500D03*
X606322Y351522D03*
X633000Y356600D03*
Y360500D03*
Y353000D03*
X636500Y356500D03*
X629500D03*
Y371000D03*
X626458Y372521D03*
X616706Y349718D03*
X618680Y346780D03*
X621300Y366900D03*
X609500Y360717D03*
X618600Y357100D03*
X623000Y382500D03*
X617000D03*
X609000Y390350D03*
X615500Y420100D03*
X619100Y418000D03*
X627600Y685000D03*
X608000Y700800D03*
X613178Y827374D03*
X606506D03*
X638375D03*
X631703D03*
X619105D03*
X625777D03*
X636640Y830301D03*
X624042D03*
X611443D03*
X633440D03*
X620842D03*
X608243D03*
X606693Y878276D03*
X619292D03*
X612992D03*
X625590D03*
X631890D03*
X630340Y875176D03*
X617742D03*
X605144D03*
X627140D03*
X614542D03*
X653300Y48600D03*
X665400Y72500D03*
X661100Y73000D03*
X662300Y63300D03*
X656700Y57400D03*
X665696Y57027D03*
X671100Y63400D03*
X656400Y102600D03*
X665100Y102700D03*
X660600Y93300D03*
X669400Y93200D03*
X659700Y86400D03*
X662400Y78100D03*
X667500Y76000D03*
X664000Y91100D03*
X671300Y78100D03*
X641159Y137800D03*
X654500Y143000D03*
X647000D03*
X643160Y149600D03*
X640150Y149650D03*
X640400Y218200D03*
X649400Y234500D03*
X671124Y210770D03*
X655500Y213500D03*
X642463Y241608D03*
X638963D03*
X660700Y212000D03*
X640532Y318099D03*
X643932Y318104D03*
X639500Y342500D03*
X652254Y336353D03*
X643000Y343000D03*
X643750Y321500D03*
X640550D03*
X662897Y346873D03*
X663140Y353982D03*
X646884Y355616D03*
X639500Y371000D03*
X643000Y369500D03*
X648792Y358431D03*
X660244Y352200D03*
Y349000D03*
X653000Y380500D03*
X644100Y488700D03*
X639500Y678500D03*
X657000Y714500D03*
X668500Y700000D03*
X648900Y782500D03*
X645800Y780500D03*
Y776900D03*
Y783900D03*
X666348Y827374D03*
X653750D03*
X660422D03*
X653500Y819100D03*
X671285Y830301D03*
X658687D03*
X668085D03*
X655487D03*
X647838Y872000D03*
X660236Y878276D03*
X666536D03*
X654000Y878200D03*
X642200Y877900D03*
X664986Y875176D03*
X652388D03*
X661786D03*
X649188D03*
X674600Y72200D03*
X676800Y46300D03*
X674300Y102400D03*
X678300Y93100D03*
X674800Y86800D03*
X687900Y208100D03*
X697494Y186256D03*
Y181919D03*
X693300Y181200D03*
X685115Y210677D03*
X674500Y212000D03*
X689500Y344000D03*
X704500Y343000D03*
X676700Y378800D03*
X687000Y378700D03*
X680100Y378718D03*
X683600D03*
X678500Y684000D03*
X673020Y827374D03*
X698217D03*
X691545D03*
X678947D03*
X685619D03*
X698100Y821600D03*
X696482Y830301D03*
X683884D03*
X693282D03*
X680684D03*
X703900Y866100D03*
X697700D03*
X704331Y878276D03*
X698031D03*
X691733D03*
X685433D03*
X679134D03*
X672834D03*
X702400Y868800D03*
X690183Y875176D03*
X677585D03*
X699200Y868800D03*
X686983Y875176D03*
X674385D03*
X728395Y-7315D03*
X713461Y-3006D03*
X736308Y-7483D03*
X711919Y6754D03*
X729132Y3575D03*
X724018Y5719D03*
X729555Y33100D03*
X709120Y35980D03*
X719555Y33100D03*
X735186Y20714D03*
X729000Y24800D03*
X725314Y24751D03*
X721890Y24887D03*
X719008Y21999D03*
X707051Y12174D03*
X738384Y8232D03*
X722955Y33095D03*
X726155D03*
X727265Y52588D03*
X726646Y42651D03*
X721690Y53340D03*
X723200Y42300D03*
X726609Y49251D03*
Y46051D03*
X732900Y44900D03*
X730021Y42235D03*
X723501Y82680D03*
X723481Y76780D03*
X723610Y106430D03*
X723569Y100969D03*
X723659Y97292D03*
X723429Y91683D03*
X735157Y97005D03*
X735326Y102660D03*
X732500Y98421D03*
X720800Y102150D03*
Y93150D03*
Y78150D03*
X732500Y101621D03*
X720800Y105350D03*
Y96350D03*
Y81350D03*
X723438Y112700D03*
X723638Y118353D03*
X720800Y114150D03*
Y117350D03*
X713000Y310000D03*
X724400Y626500D03*
X712495Y816195D03*
X735640Y827374D03*
X723041D03*
X729713D03*
X727978Y830301D03*
X737377D03*
X724778D03*
X714900Y818600D03*
X729527Y878276D03*
X735827D03*
X723000Y878200D03*
X734277Y875176D03*
X731077D03*
X746329Y-7789D03*
X771715Y6840D03*
X752763Y38638D03*
X771600Y24200D03*
X741600Y41000D03*
X747000Y44300D03*
X762250Y44650D03*
X742290Y68550D03*
X750130Y63340D03*
X748300Y53800D03*
X772000Y64200D03*
X753500Y96600D03*
X755700Y79100D03*
X749800Y91400D03*
X753700Y102900D03*
X759600Y79200D03*
X762400Y127600D03*
X753500Y110900D03*
X769400Y111900D03*
X743490Y111940D03*
X765000Y112800D03*
X768777Y171450D03*
X761242Y169242D03*
X765579D03*
X771400Y185919D03*
X766244Y185897D03*
X748237Y194042D03*
X751737D03*
X766950Y189252D03*
X763562Y189539D03*
X770385Y189165D03*
X749337Y212192D03*
X746037Y213992D03*
X746237Y210392D03*
X743500Y362000D03*
X753000Y359000D03*
X743000Y598000D03*
X773435Y827374D03*
X754910D03*
X748238D03*
X742312D03*
X760837D03*
X767509D03*
X765774Y830301D03*
X753175D03*
X740577D03*
X762574D03*
X749975D03*
X754724Y878276D03*
X761024D03*
X767323D03*
X742126D03*
X748426D03*
X772073Y875176D03*
X759474D03*
X746876D03*
X768873D03*
X756274D03*
X743676D03*
X790150Y-1400D03*
X788408Y-4321D03*
X798061Y-6439D03*
X788550Y29350D03*
X806152Y51692D03*
X791300Y74200D03*
X775381Y66115D03*
X778800Y66388D03*
X782551Y67144D03*
X786333Y66963D03*
X781500Y85100D03*
X797800Y104500D03*
X776538Y107162D03*
X773900Y138300D03*
X791200Y125300D03*
X796051Y175147D03*
X806665Y174050D03*
X803265D03*
X792760Y176043D03*
X799000Y196000D03*
X802200D03*
X796089Y181182D03*
X775397Y179165D03*
Y184215D03*
X792390Y199166D03*
X786463Y199019D03*
X803169Y198850D03*
X797890Y198918D03*
X792000Y195778D03*
X787600Y195804D03*
X773984Y189118D03*
X792760Y180443D03*
X778807Y183890D03*
Y179490D03*
X780800Y545900D03*
X786033Y827374D03*
X780107D03*
X792705D03*
X798632D03*
X805304D03*
X803569Y830301D03*
X790970D03*
X778372D03*
X800369D03*
X787770D03*
X775172D03*
X779921Y878276D03*
X786221D03*
X792519D03*
X798819D03*
X805118D03*
X773623D03*
X797270Y875176D03*
X784671D03*
X806668D03*
X794070D03*
X781471D03*
X807514Y2199D03*
X813900Y12900D03*
X830773Y9000D03*
X834227D03*
X831592Y34411D03*
X838252Y20800D03*
X834500D03*
X830500D03*
X828283Y24734D03*
X824462Y25770D03*
X821877Y21090D03*
X823996Y44276D03*
X832401Y46472D03*
X831125Y67775D03*
X820004Y44234D03*
X828700Y48800D03*
X808114Y67634D03*
X816043Y94981D03*
Y99318D03*
X823551Y80551D03*
X819000Y97100D03*
X809000Y76000D03*
X810000Y109400D03*
X833900Y467000D03*
X812500Y499400D03*
X840500Y735500D03*
X837000D03*
X839990Y789230D03*
X836427Y827374D03*
X817902D03*
X811230D03*
X816167Y830301D03*
X838164D03*
X812967D03*
X836615Y878276D03*
X830315D03*
X811418D03*
X820000Y878200D03*
X835065Y875176D03*
X809868D03*
X831865D03*
X861000Y350D03*
X857453Y303D03*
X867600Y2500D03*
X863300Y23575D03*
X851100Y9100D03*
X855489Y9811D03*
X859300Y9900D03*
X874300Y18875D03*
X858500Y40000D03*
Y32000D03*
X869447Y31024D03*
X843500Y9150D03*
X849051Y20908D03*
X845052Y20800D03*
X841652D03*
X858500Y28000D03*
X858100Y21400D03*
X858500Y36000D03*
X847000Y9100D03*
X870600Y18915D03*
X854252Y20800D03*
X851870Y52160D03*
X859200Y47100D03*
X847337Y46563D03*
X851300Y45748D03*
X848623Y70757D03*
X852019Y70589D03*
X855421Y70551D03*
X858821Y70614D03*
X859000Y43500D03*
X871550Y56450D03*
X858800Y52200D03*
X868800Y49200D03*
X844900Y85100D03*
X868800Y85300D03*
X871696Y87082D03*
X868200Y116000D03*
X846702Y117371D03*
X854400Y117500D03*
X861300Y117800D03*
X851500Y705500D03*
X864800Y707700D03*
X868200D03*
X852500Y718000D03*
X847500Y717500D03*
X857406Y745598D03*
X861406Y745531D03*
X852895Y748648D03*
X869406Y745531D03*
X848000Y735500D03*
X865406Y745598D03*
X873367Y745335D03*
X844000Y735500D03*
X855500Y775500D03*
X844150Y762150D03*
X858695Y759900D03*
X871000Y776500D03*
X854049Y757573D03*
X857406Y755198D03*
X861406D03*
X858126Y763600D03*
X841500Y771000D03*
X874000Y772000D03*
X869562Y758457D03*
X844500Y758000D03*
X867410Y755824D03*
X849906Y804531D03*
X865378Y804431D03*
X851890Y789270D03*
X870900Y812104D03*
X866878Y794531D03*
X853500Y798000D03*
X846706Y797648D03*
X870278Y794531D03*
X874570Y811820D03*
X861406Y804403D03*
X857406D03*
X855697Y827374D03*
X849025D03*
X843099D03*
X853962Y830301D03*
X841364D03*
X850762D03*
X861823Y853696D03*
X849213Y878276D03*
X842913D03*
X856000Y878200D03*
X847663Y875176D03*
X844463D03*
X883800Y-500D03*
X881700Y2300D03*
X899769Y4355D03*
X904262Y14894D03*
X887800Y40100D03*
X880883Y30583D03*
X892745Y9681D03*
X896500Y9500D03*
X877500Y23600D03*
X900250Y38150D03*
X888474Y9173D03*
X900200Y9600D03*
X883800Y41400D03*
X907750Y51750D03*
X894110Y49250D03*
X878800Y49600D03*
X875050Y56250D03*
X895080Y52828D03*
X900501Y48705D03*
X883700Y50700D03*
X905488Y54479D03*
X890000Y97800D03*
X897000Y96700D03*
X878394Y85780D03*
X875001Y86003D03*
X901899Y85942D03*
X892900Y85300D03*
X885042Y85292D03*
X888600Y85700D03*
X897600Y85500D03*
X908500Y270500D03*
Y275000D03*
Y267000D03*
X907500Y325000D03*
X902500Y370000D03*
X897000Y370500D03*
X907500Y368000D03*
X900999Y748550D03*
X885400Y743600D03*
X895800Y738400D03*
X893400Y745100D03*
X884700Y721100D03*
X896500Y734000D03*
X877000Y745000D03*
X892100Y721100D03*
X881200Y721300D03*
X888400Y721400D03*
X900824Y781531D03*
X895278Y758885D03*
X874887Y759253D03*
X884671Y775500D03*
X889900Y769600D03*
X884778Y756198D03*
X876036Y755481D03*
X894465Y755501D03*
X891056Y755641D03*
X882227Y758835D03*
X885167Y816593D03*
X894200Y794500D03*
X877930Y796880D03*
X876470Y808710D03*
X906396Y810300D03*
X886288Y794372D03*
X898700Y794200D03*
Y816000D03*
X882290Y796770D03*
X881720Y807390D03*
X906450Y806900D03*
X906092Y813687D03*
X884412Y835051D03*
X894406Y818000D03*
X888100Y823338D03*
X890200Y819200D03*
X912000Y41000D03*
X927250Y31450D03*
X911800Y37000D03*
X938000Y30300D03*
X919400Y33300D03*
X915486Y41030D03*
X918952Y40680D03*
X912000Y45000D03*
X939064Y58104D03*
X934881Y57322D03*
X909797Y55037D03*
X910000Y85300D03*
X937642Y85562D03*
X926093Y85239D03*
X929213Y86593D03*
X934438Y86700D03*
X919050Y85500D03*
X913979Y86580D03*
X935000Y97400D03*
X927100Y96900D03*
X929800Y105900D03*
X909000Y279000D03*
X909500Y283000D03*
Y338000D03*
X909000Y353600D03*
X908700Y347300D03*
X938898Y640169D03*
X916319Y678588D03*
Y658588D03*
Y698588D03*
Y738588D03*
Y718588D03*
Y778588D03*
Y758588D03*
Y798588D03*
Y818588D03*
X969100Y14600D03*
X942500Y30100D03*
X974100Y19600D03*
X970064Y18764D03*
X963700Y21700D03*
X959877Y26978D03*
X967180Y66705D03*
X952500Y75100D03*
X949102Y74964D03*
X947900Y67900D03*
X959300Y68600D03*
Y72000D03*
X964105Y62308D03*
X959855Y61107D03*
X956687Y85482D03*
X942800Y85700D03*
X948200Y85900D03*
X953301Y85793D03*
X956500Y108000D03*
X949500Y103000D03*
Y97500D03*
X949893Y106378D03*
X949828Y109778D03*
X957800Y570300D03*
X960500Y607000D03*
X953500D03*
X956900D03*
X958898Y640169D03*
X976500Y4500D03*
X1008353Y-1940D03*
X985579Y26494D03*
X985403Y22993D03*
X980100Y14500D03*
X1000985Y29307D03*
X1007921Y39585D03*
X985315Y14425D03*
X997385Y29307D03*
X994650Y39880D03*
X992396Y45073D03*
X990628Y49698D03*
X997007Y49560D03*
X1008508Y47704D03*
X982500Y271500D03*
Y275500D03*
X982000Y267500D03*
X983500Y279500D03*
Y283500D03*
X1006100Y528700D03*
X977500Y550000D03*
X978898Y640169D03*
X994248Y665818D03*
Y685818D03*
Y705818D03*
Y745818D03*
Y725818D03*
Y765818D03*
Y805818D03*
Y785818D03*
X1025700Y7600D03*
X1022711Y-4975D03*
X1012177Y-2940D03*
X1019859Y-7642D03*
X1033017Y14743D03*
X1024330Y34379D03*
X1040218Y32140D03*
X1010229Y19022D03*
X1022300Y13900D03*
X1033554Y30216D03*
X1040121Y26870D03*
X1039822Y35743D03*
X1017908Y41556D03*
X1018900Y14198D03*
X1010975Y29017D03*
X1029553Y13981D03*
X1030139Y30209D03*
X1024432Y43718D03*
X1035783Y51473D03*
X1017863Y45056D03*
X1011300Y53000D03*
X1024318Y51554D03*
X1014700Y53700D03*
X1040241Y61043D03*
X1033517Y48934D03*
X1036854Y47110D03*
X1019900Y108500D03*
X1015948D03*
X1034500D03*
X1027483Y108431D03*
X1024000Y108500D03*
X1037900D03*
X1041300D03*
X1030883Y108438D03*
X1028500Y257500D03*
X1012600Y476700D03*
X1022600Y542100D03*
X1017800Y572700D03*
X1043300Y631300D03*
X1041500Y682000D03*
X1041900Y658100D03*
X1039577Y827374D03*
X1041314Y830301D03*
X1024004Y855893D03*
X1033464Y878276D03*
X1039764D03*
X1038214Y875176D03*
X1035014D03*
X1062044Y-4173D03*
X1065620Y-4335D03*
X1072800Y-800D03*
X1069261Y-14185D03*
X1049261D03*
X1045850Y6228D03*
X1069200Y-4200D03*
X1060800Y10100D03*
X1061253Y17487D03*
X1062470Y31823D03*
X1062433Y37099D03*
X1056049Y18396D03*
X1061153Y27488D03*
X1046200Y24500D03*
X1054835Y40386D03*
X1072140Y16447D03*
X1047429Y15229D03*
X1044050Y28815D03*
X1062088Y40597D03*
X1072804Y19894D03*
X1064900Y10400D03*
X1065700Y32888D03*
Y36088D03*
X1061200Y20888D03*
Y24088D03*
X1056200Y10100D03*
X1065657Y28946D03*
X1047500Y41500D03*
X1051000D03*
X1076970Y30411D03*
X1052600Y14400D03*
X1054210Y53370D03*
X1054090Y58470D03*
X1068315Y56120D03*
X1068390Y61611D03*
X1074103Y44988D03*
X1049772Y57259D03*
X1049470Y53749D03*
X1050875Y61090D03*
X1057000Y54500D03*
X1071135Y60375D03*
X1057000Y57700D03*
X1071135Y57175D03*
X1057000Y107700D03*
X1057259Y77276D03*
X1048100Y108500D03*
X1044700D03*
X1061000Y111000D03*
X1053000Y109500D03*
X1047000Y644000D03*
X1045000Y617500D03*
X1067000Y711000D03*
X1062500Y738000D03*
X1058500Y758000D03*
X1058847Y827374D03*
X1052175D03*
X1046249D03*
X1064774D03*
X1071446D03*
X1069711Y830301D03*
X1057112D03*
X1044514D03*
X1066511D03*
X1053912D03*
X1046063Y878276D03*
X1071260D03*
X1064961D03*
X1058661D03*
X1052363D03*
X1076010Y875176D03*
X1050813D03*
X1072810D03*
X1047613D03*
X1084000Y500D03*
X1089261Y-14185D03*
X1083315Y36654D03*
X1082808Y30601D03*
X1092094Y30362D03*
X1080672Y9500D03*
X1084800Y9400D03*
X1083379Y40889D03*
X1083500Y25500D03*
X1082974Y14467D03*
X1105441Y54768D03*
X1100992Y52374D03*
X1078694Y43478D03*
X1103424Y67690D03*
X1077432Y64225D03*
X1103300Y73900D03*
X1103349Y70700D03*
X1088005Y46541D03*
X1088287Y55917D03*
X1096496Y51226D03*
X1110664Y78483D03*
X1103253Y76910D03*
X1079500Y631000D03*
X1080000Y650500D03*
X1081000Y670000D03*
X1084044Y827374D03*
X1077372D03*
X1102569D03*
X1109241D03*
X1089970D03*
X1096642D03*
X1107506Y830301D03*
X1094907D03*
X1082309D03*
X1104306D03*
X1091707D03*
X1079109D03*
X1090158Y878276D03*
X1083858D03*
X1077560D03*
X1096456D03*
X1102756D03*
X1109055D03*
X1101207Y875176D03*
X1088608D03*
X1110605D03*
X1098007D03*
X1085408D03*
X1127300Y46300D03*
X1122800Y55100D03*
X1132100Y56300D03*
X1131900Y70700D03*
X1140900Y71100D03*
X1141900Y63300D03*
X1142418Y78638D03*
X1131800Y85600D03*
X1141200Y86800D03*
X1126400Y92200D03*
X1143500Y93300D03*
X1123000Y99200D03*
X1131880Y100377D03*
X1134800Y93300D03*
X1116933Y85243D03*
X1112700Y80700D03*
X1114842Y83078D03*
X1122001Y126574D03*
Y136874D03*
X1135150Y137851D03*
X1122001Y133324D03*
X1141900Y137851D03*
X1122001Y130124D03*
X1138700Y137851D03*
X1126500Y222500D03*
X1135750Y228750D03*
X1143000Y242000D03*
X1140364Y827374D03*
X1121839D03*
X1115167D03*
X1127766D03*
X1134438D03*
X1132703Y830301D03*
X1120104D03*
X1142101D03*
X1129503D03*
X1116904D03*
X1140552Y878276D03*
X1115355D03*
X1127953D03*
X1134252D03*
X1121653D03*
X1139002Y875176D03*
X1126403D03*
X1113805D03*
X1135802D03*
X1123203D03*
X1175300Y71100D03*
X1175100Y55700D03*
X1166500Y56200D03*
X1171700Y45900D03*
X1149100Y46300D03*
X1150700Y63300D03*
X1148900Y75900D03*
X1168400Y103000D03*
X1177000Y102800D03*
X1176200Y92900D03*
X1178100Y78000D03*
X1175200Y85900D03*
X1151492Y78668D03*
X1164857Y138505D03*
X1154557D03*
X1145450Y137851D03*
X1175851Y142410D03*
X1161307Y138505D03*
X1158107D03*
X1170400Y144100D03*
X1150250Y228750D03*
X1147000Y242000D03*
X1151000D03*
X1161700Y818500D03*
X1159634Y827374D03*
X1152962D03*
X1147036D03*
X1175010D03*
X1174900Y818300D03*
X1157899Y830301D03*
X1145301D03*
X1176747D03*
X1154699D03*
X1159448Y878276D03*
X1153150D03*
X1173623Y878200D03*
X1146850Y878276D03*
X1165748D03*
X1164199Y875176D03*
X1151600D03*
X1160999D03*
X1148400D03*
X1185200Y72600D03*
X1210511Y52300D03*
X1193555Y61875D03*
X1183884Y61598D03*
X1188200Y61600D03*
X1192300Y46100D03*
X1184100Y56100D03*
X1193900Y78000D03*
X1211500Y102900D03*
X1194000Y93200D03*
X1185800Y102900D03*
X1185100Y93000D03*
X1187100Y77900D03*
X1184800Y87200D03*
X1202410Y142850D03*
X1193845Y137855D03*
X1184629Y137740D03*
X1185070Y142384D03*
X1182061Y142478D03*
X1190835Y137899D03*
X1199400Y142851D03*
X1178861Y142478D03*
X1187635Y137899D03*
X1196200Y142851D03*
X1210391Y156730D03*
X1200391Y156779D03*
X1193192Y142970D03*
X1206991Y156730D03*
X1203791D03*
X1205500Y334400D03*
X1201000Y417900D03*
X1196600Y416200D03*
X1194280Y827374D03*
X1187608D03*
X1181682D03*
X1192545Y830301D03*
X1179947D03*
X1189345D03*
X1200735Y864273D03*
X1194063D03*
X1200394Y878276D03*
X1194094D03*
X1187796D03*
X1181496D03*
X1199000Y867200D03*
X1186246Y875176D03*
X1195800Y867300D03*
X1183046Y875176D03*
X1231400Y58300D03*
X1215400Y57600D03*
X1216300Y72900D03*
X1235800Y46400D03*
X1228000Y57000D03*
X1218600Y56000D03*
X1214700Y46000D03*
X1221200Y63400D03*
X1230300Y63200D03*
X1228900Y72900D03*
X1230000Y78800D03*
X1221300Y78400D03*
X1219200Y87000D03*
X1229100Y87900D03*
X1232500Y90900D03*
X1229900Y103100D03*
X1228300Y93100D03*
X1219500Y93300D03*
X1220100Y102700D03*
X1219138Y137928D03*
X1227999Y142465D03*
X1236692Y137720D03*
X1237219Y142420D03*
X1228359Y137960D03*
X1214795Y142443D03*
X1234209Y142463D03*
X1242900Y137851D03*
X1225348Y137960D03*
X1231009Y142463D03*
X1239700Y137851D03*
X1222148Y137960D03*
X1242621Y153690D03*
X1226000Y261300D03*
X1242000Y343000D03*
X1235400Y364400D03*
X1213400Y355400D03*
X1214100Y469800D03*
X1237800Y524500D03*
X1232300Y568900D03*
X1238375Y827374D03*
X1231703D03*
X1219105D03*
X1225777D03*
X1244302D03*
X1236640Y830301D03*
X1224042D03*
X1233440D03*
X1220842D03*
X1217717Y878076D03*
X1225590Y878276D03*
X1231890D03*
X1244489D03*
X1238189D03*
X1242939Y875176D03*
X1230340D03*
X1239739D03*
X1227140D03*
X1261900Y71039D03*
X1265500Y61900D03*
X1272200Y72900D03*
X1275200Y61200D03*
X1269900Y61100D03*
X1279100Y46300D03*
X1272200Y57900D03*
X1258400Y45900D03*
X1254500Y51100D03*
X1271300Y77100D03*
X1273200Y103200D03*
X1256000Y103300D03*
X1263200Y102700D03*
X1270300Y91100D03*
X1262800Y93100D03*
X1254200Y96300D03*
X1275500Y91000D03*
X1272700Y88000D03*
X1265200Y77400D03*
X1261900Y86000D03*
X1275800Y75900D03*
X1252768Y141181D03*
X1278160Y140547D03*
X1257899Y142881D03*
X1245910Y137810D03*
X1273068Y140514D03*
X1277265Y137673D03*
X1274065D03*
X1262880Y142909D03*
X1273499Y151498D03*
X1273520Y148070D03*
X1261944Y145770D03*
X1258744D03*
X1251801Y144871D03*
X1275500Y264500D03*
X1258500Y335500D03*
X1266500D03*
X1255000Y317300D03*
X1270500Y335500D03*
X1272500Y350000D03*
X1275060Y345690D03*
X1277620Y349500D03*
X1264820Y349320D03*
X1273500Y397000D03*
X1257500D03*
X1254000D03*
X1249250Y390250D03*
X1269500Y397000D03*
X1273500Y400500D03*
X1258000Y421500D03*
X1259200Y471800D03*
X1259000Y680000D03*
X1265000Y672000D03*
X1253500D03*
X1278000Y689000D03*
X1263572Y827374D03*
X1269498D03*
X1276170D03*
X1256900D03*
X1250974D03*
X1274435Y830301D03*
X1261837D03*
X1249239D03*
X1271235D03*
X1258637D03*
X1246039D03*
X1263386Y878276D03*
X1275984D03*
X1257087D03*
X1269686D03*
X1250787D03*
X1268136Y875176D03*
X1255537D03*
X1277534D03*
X1264936D03*
X1252337D03*
X1303983Y22083D03*
X1304000Y44000D03*
Y67500D03*
Y90500D03*
X1291660Y140257D03*
X1297360Y140172D03*
X1301749Y125479D03*
X1286543Y141581D03*
X1296017Y137478D03*
X1283343Y141581D03*
X1292817Y137478D03*
X1282189Y144361D03*
X1287637Y144386D03*
X1297668Y155524D03*
X1290870Y186285D03*
X1311181Y186548D03*
X1290000Y271000D03*
X1308500Y262500D03*
X1311200Y256500D03*
X1293500Y271000D03*
X1312200Y275200D03*
X1303700Y289500D03*
X1288900Y304000D03*
X1283300Y302900D03*
X1309900Y292400D03*
X1310500Y285500D03*
X1297500Y351800D03*
X1281900Y346580D03*
X1282740Y350010D03*
X1293280Y345770D03*
X1289960Y349900D03*
X1299000Y347500D03*
X1311500Y391000D03*
X1310068Y394084D03*
X1297625Y382375D03*
X1296500Y386500D03*
X1290125Y382875D03*
X1289500Y386500D03*
X1282740Y383000D03*
X1282000Y386500D03*
X1291600Y495200D03*
X1296400Y542400D03*
X1294700Y593400D03*
X1301000Y618500D03*
X1300000Y637000D03*
X1302128Y674067D03*
X1306128Y674000D03*
X1297617Y677117D03*
X1286800Y671100D03*
X1297500Y664000D03*
X1310207D03*
X1297400Y651300D03*
X1290550D03*
X1285000Y694000D03*
X1280500Y706000D03*
X1310376Y687205D03*
X1301728Y711200D03*
X1302000Y695500D03*
X1302128Y685500D03*
X1307000Y686500D03*
X1304500Y698000D03*
X1301728Y714600D03*
X1312132Y684293D03*
X1310100Y732900D03*
X1294628Y733000D03*
X1310500Y723000D03*
X1291428Y726117D03*
X1306128Y732872D03*
X1302128D03*
X1304800Y811900D03*
X1288768Y827374D03*
X1282096D03*
X1307294D03*
X1312231Y830301D03*
X1287033D03*
X1309031D03*
X1283833D03*
X1301800Y878100D03*
X1294268Y872169D03*
X1288582Y878276D03*
X1282284D03*
X1307481D03*
X1305931Y875176D03*
X1293333D03*
X1280734D03*
X1302731D03*
X1290133D03*
X1324845Y130527D03*
X1339471Y139268D03*
X1325429Y148270D03*
X1316590Y147210D03*
X1317400Y143620D03*
X1340130Y145980D03*
X1331243Y182198D03*
X1337000Y263250D03*
X1332000Y261500D03*
Y265000D03*
Y268500D03*
Y272500D03*
Y257500D03*
Y254000D03*
X1342000D03*
Y257500D03*
Y261500D03*
Y265000D03*
Y268500D03*
Y272500D03*
X1337000Y267500D03*
Y272000D03*
Y259000D03*
Y254500D03*
X1322000Y276500D03*
X1322500Y266800D03*
X1333500Y290500D03*
X1317026Y304858D03*
X1322250Y282250D03*
X1314000Y286500D03*
X1345850Y676750D03*
X1313607Y664000D03*
X1327200Y661800D03*
X1331000Y662000D03*
X1326128Y674000D03*
X1340000D03*
X1317007Y664000D03*
X1334128Y674000D03*
X1333500Y709500D03*
X1323076Y686999D03*
X1338200Y689800D03*
X1315546Y709500D03*
X1341400Y686900D03*
X1337500Y698000D03*
X1322439Y697767D03*
X1315000Y686500D03*
X1329500Y684667D03*
X1321928Y683798D03*
X1318500Y684667D03*
X1339934Y683832D03*
X1336795Y685141D03*
X1326758Y686678D03*
X1314628Y733000D03*
X1315000Y723000D03*
X1326661Y740700D03*
X1333500Y723000D03*
X1334128Y732667D03*
X1325600Y722987D03*
X1342000Y732500D03*
X1337500Y723000D03*
X1340500Y742500D03*
X1338128Y732872D03*
X1330128Y732667D03*
X1345088Y827374D03*
X1332490D03*
X1339162D03*
X1326564D03*
X1319892D03*
X1313966D03*
X1337427Y830301D03*
X1324829D03*
X1346825D03*
X1334227D03*
X1321629D03*
X1320079Y878276D03*
X1345276D03*
X1332678D03*
X1338976D03*
X1326378D03*
X1313779D03*
X1343726Y875176D03*
X1331128D03*
X1318529D03*
X1340526D03*
X1327928D03*
X1315329D03*
X1368028Y175745D03*
X1359128Y167226D03*
X1355321Y172119D03*
X1354971Y167446D03*
X1365804Y185197D03*
X1368300Y267800D03*
X1358662Y275485D03*
X1355066Y275228D03*
X1348500Y276500D03*
X1361500Y273500D03*
X1352000Y276700D03*
X1352500Y267000D03*
X1369300Y259300D03*
X1355000Y286300D03*
X1364000Y280500D03*
X1369700Y424600D03*
X1366000Y472900D03*
X1363900Y537600D03*
X1361800Y596800D03*
X1358700Y655700D03*
X1351500Y675000D03*
X1348500Y713000D03*
X1377000Y725000D03*
X1378000Y806900D03*
X1369925Y835051D03*
X1351760Y827374D03*
X1350025Y830301D03*
X1357886Y864246D03*
X1352200Y878400D03*
X1394500Y139626D03*
Y119626D03*
Y159626D03*
X1381696Y173459D03*
X1387196Y174160D03*
X1394500Y199626D03*
Y179626D03*
X1381568Y180579D03*
X1382138Y184129D03*
X1385467Y180543D03*
X1394500Y239626D03*
Y219626D03*
Y259626D03*
Y299626D03*
Y279626D03*
Y339626D03*
Y319626D03*
Y359626D03*
Y399626D03*
Y379626D03*
Y439626D03*
Y419626D03*
Y479626D03*
Y459626D03*
Y499626D03*
Y539626D03*
Y519626D03*
Y579626D03*
Y559626D03*
Y599626D03*
Y639626D03*
Y619626D03*
Y679626D03*
Y659626D03*
Y699626D03*
Y739626D03*
Y719626D03*
Y759626D03*
Y779626D03*
Y799626D03*
Y819626D03*
X1389925Y835051D03*
X1708976Y855906D03*
G54D21*
X113300Y276600D03*
X131700Y275700D03*
X113000Y280500D03*
X113100Y284100D03*
X125100Y282500D03*
X131700Y280000D03*
X294000Y716000D03*
X300500Y715613D03*
X528100Y767300D03*
X1708976Y827806D03*
G54D12*
X31977Y126614D03*
Y116614D03*
X91189Y126614D03*
Y116614D03*
Y136614D03*
X1708976Y546806D03*
G54D30*
X533010Y69803D03*
X530057Y67048D03*
X535962Y64292D03*
X524151Y69803D03*
X527104Y64292D03*
X535962Y49331D03*
X527104D03*
X530057Y52087D03*
X533010Y54843D03*
X524151D03*
X533010Y99725D03*
X530057Y96969D03*
X535962Y94213D03*
X524151Y99725D03*
X527104Y94213D03*
X533010Y84764D03*
X530057Y82008D03*
X535962Y79252D03*
X524151Y84764D03*
X527104Y79252D03*
X567458Y54843D03*
X570411Y49331D03*
Y64292D03*
X567458Y69803D03*
X541868D03*
X538915Y67048D03*
X547773D03*
X544821Y64292D03*
Y49331D03*
X547773Y52087D03*
X538915D03*
X541868Y54843D03*
X570411Y79252D03*
Y94213D03*
X567458Y84764D03*
Y99725D03*
X541868D03*
X538915Y96969D03*
X547773D03*
X544821Y94213D03*
X541868Y84764D03*
X538915Y82008D03*
X547773D03*
X544821Y79252D03*
X576317Y54843D03*
X585175D03*
X573364Y52087D03*
X582222D03*
X591080D03*
X579269Y49331D03*
X588128D03*
X576317Y69803D03*
X585175D03*
X573364Y67048D03*
X582222D03*
X591080D03*
X579269Y64292D03*
X588128D03*
X579269Y79252D03*
X588128D03*
X582222Y82008D03*
X591080D03*
X585175Y84764D03*
X576317D03*
X573364Y82008D03*
X576317Y99725D03*
X585175D03*
X573364Y96969D03*
X582222D03*
X579269Y94213D03*
X588128D03*
X591080Y96969D03*
X619624Y54843D03*
X628482D03*
X616671Y52087D03*
X625529D03*
X634388D03*
X622577Y49331D03*
X631435D03*
X619624Y69803D03*
X628482D03*
X616671Y67048D03*
X625529D03*
X634388D03*
X622577Y64292D03*
X631435D03*
X610766Y54843D03*
X613718Y49331D03*
Y64292D03*
X610766Y69803D03*
X622577Y79252D03*
X631435D03*
X625529Y82008D03*
X634388D03*
X628482Y84764D03*
X619624D03*
X616671Y82008D03*
X619624Y99725D03*
X628482D03*
X616671Y96969D03*
X625529D03*
X622577Y94213D03*
X631435D03*
X634388Y96969D03*
X613718Y79252D03*
Y94213D03*
X610766Y84764D03*
Y99725D03*
X662931Y54843D03*
X671789D03*
X659978Y52087D03*
X668836D03*
X665884Y49331D03*
X662931Y69803D03*
X671789D03*
X659978Y67048D03*
X668836D03*
X665884Y64292D03*
X654073Y54843D03*
X657025Y49331D03*
Y64292D03*
X654073Y69803D03*
X665884Y79252D03*
X668836Y82008D03*
X671789Y84764D03*
X662931D03*
X659978Y82008D03*
X662931Y99725D03*
X671789D03*
X659978Y96969D03*
X668836D03*
X665884Y94213D03*
X657025Y79252D03*
Y94213D03*
X654073Y84764D03*
Y99725D03*
X677695Y52087D03*
X674742Y49331D03*
X677695Y67048D03*
X674742Y64292D03*
Y79252D03*
X677695Y82008D03*
X674742Y94213D03*
X677695Y96969D03*
X1135372Y69803D03*
X1144230D03*
X1132419Y67048D03*
X1141277D03*
X1138324Y64292D03*
X1126513Y69803D03*
X1129466Y64292D03*
X1138324Y49331D03*
X1129466D03*
X1141277Y52087D03*
X1132419D03*
X1144230Y54843D03*
X1135372D03*
X1126513D03*
X1135372Y99725D03*
X1144230D03*
X1132419Y96969D03*
X1141277D03*
X1138324Y94213D03*
X1126513Y99725D03*
X1129466Y94213D03*
X1135372Y84764D03*
X1144230D03*
X1132419Y82008D03*
X1141277D03*
X1138324Y79252D03*
X1126513Y84764D03*
X1129466Y79252D03*
X1178679Y54843D03*
X1175726Y52087D03*
X1178679Y69803D03*
X1175726Y67048D03*
X1169820Y54843D03*
X1172773Y49331D03*
Y64292D03*
X1169820Y69803D03*
X1150135Y67048D03*
X1147183Y64292D03*
Y49331D03*
X1150135Y52087D03*
X1178679Y84764D03*
X1175726Y82008D03*
X1178679Y99725D03*
X1175726Y96969D03*
X1172773Y79252D03*
Y94213D03*
X1169820Y84764D03*
Y99725D03*
X1150135Y96969D03*
X1147183Y94213D03*
X1150135Y82008D03*
X1147183Y79252D03*
X1187537Y54843D03*
X1184584Y52087D03*
X1193442D03*
X1181631Y49331D03*
X1190490D03*
X1187537Y69803D03*
X1184584Y67048D03*
X1193442D03*
X1181631Y64292D03*
X1190490D03*
X1181631Y79252D03*
X1190490D03*
X1184584Y82008D03*
X1193442D03*
X1187537Y84764D03*
Y99725D03*
X1184584Y96969D03*
X1181631Y94213D03*
X1190490D03*
X1193442Y96969D03*
X1221986Y54843D03*
X1230844D03*
X1219033Y52087D03*
X1227891D03*
X1236750D03*
X1224939Y49331D03*
X1233797D03*
X1221986Y69803D03*
X1230844D03*
X1219033Y67048D03*
X1227891D03*
X1236750D03*
X1224939Y64292D03*
X1233797D03*
X1213128Y54843D03*
X1216080Y49331D03*
Y64292D03*
X1213128Y69803D03*
X1224939Y79252D03*
X1233797D03*
X1227891Y82008D03*
X1236750D03*
X1230844Y84764D03*
X1221986D03*
X1219033Y82008D03*
X1221986Y99725D03*
X1230844D03*
X1219033Y96969D03*
X1227891D03*
X1224939Y94213D03*
X1233797D03*
X1236750Y96969D03*
X1216080Y79252D03*
Y94213D03*
X1213128Y84764D03*
Y99725D03*
X1265293Y54843D03*
X1274151D03*
X1262340Y52087D03*
X1271198D03*
X1280057D03*
X1268246Y49331D03*
X1277104D03*
X1265293Y69803D03*
X1274151D03*
X1262340Y67048D03*
X1271198D03*
X1280057D03*
X1268246Y64292D03*
X1277104D03*
X1256435Y54843D03*
X1259387Y49331D03*
Y64292D03*
X1256435Y69803D03*
X1268246Y79252D03*
X1277104D03*
X1271198Y82008D03*
X1280057D03*
X1274151Y84764D03*
X1265293D03*
X1262340Y82008D03*
X1265293Y99725D03*
X1274151D03*
X1262340Y96969D03*
X1271198D03*
X1268246Y94213D03*
X1277104D03*
X1280057Y96969D03*
X1259387Y79252D03*
Y94213D03*
X1256435Y84764D03*
Y99725D03*
X1708976Y799706D03*
G54D13*
X26977Y151614D03*
X96189D03*
X1708976Y518706D03*
G54D31*
X526215Y184000D03*
X565585D03*
X1708976Y293906D03*
G54D22*
X122700Y476100D03*
Y478400D03*
X122600Y473800D03*
Y471500D03*
X121673Y491672D03*
X130985Y504300D03*
X124822Y504271D03*
X127973Y504272D03*
X121673Y497973D03*
Y494822D03*
X118524Y491672D03*
X118500Y504238D03*
X115373Y504271D03*
X127973Y510571D03*
X124823D03*
X121673D03*
X131121Y513721D03*
X121673D03*
X131121Y510570D03*
X127971Y513721D03*
X124821D03*
X127971Y494823D03*
X131122Y491674D03*
X127973Y488524D03*
X131122D03*
Y485374D03*
X121673Y504272D03*
X124823Y501122D03*
X121673D03*
X127973Y497973D03*
X124822Y488523D03*
X127973Y491674D03*
X124823Y497973D03*
Y491674D03*
X127973Y485374D03*
X124823Y494822D03*
X131121Y494823D03*
X127973Y501122D03*
Y529469D03*
X124823Y523170D03*
Y542067D03*
X127973Y532618D03*
Y542067D03*
X124823Y532617D03*
X124822Y545216D03*
X131122Y532618D03*
X124823Y535766D03*
X127973Y538918D03*
X127996Y535781D03*
X121673Y545215D03*
Y523170D03*
X131121Y529467D03*
Y520018D03*
X127971D03*
X131121Y523168D03*
X124822Y520019D03*
X121673Y520020D03*
X115374Y529467D03*
X118524D03*
X121673D03*
X124823D03*
X121673Y532617D03*
X124822Y538917D03*
X121673Y535766D03*
X127973Y523170D03*
X121673Y538916D03*
X126869Y577770D03*
X122547Y564452D03*
Y558100D03*
Y551748D03*
X121601Y574686D03*
X126801Y574386D03*
X124900Y559638D03*
X124847Y550110D03*
X124900Y556462D03*
Y565990D03*
Y562814D03*
Y553286D03*
X122547Y561276D03*
Y554924D03*
Y567628D03*
X131369Y610945D03*
X115622Y604646D03*
X121911Y614076D03*
X131369Y588898D03*
X121922Y592048D03*
X118771Y595196D03*
X125072Y610945D03*
X125070Y598347D03*
X131370Y601496D03*
X118773Y601495D03*
X126646Y606400D03*
X115622Y614094D03*
Y601496D03*
X121922Y610945D03*
X128220Y614095D03*
X118773Y604645D03*
X125070Y614095D03*
X118773Y598345D03*
X118805Y614099D03*
X115623Y598345D03*
X118773Y610945D03*
X131369Y614095D03*
X118773Y589748D03*
X128221Y610945D03*
X121922Y588872D03*
X118773Y592048D03*
X121922Y617244D03*
X128221D03*
X131369D03*
X118771D03*
X125070D03*
X125072Y620392D03*
X121921D03*
X140571Y491674D03*
X140570Y488523D03*
X162618Y485374D03*
X150020Y491674D03*
X156319Y485374D03*
X146870Y491674D03*
Y482225D03*
X150020Y510571D03*
X153169D03*
X146870D03*
X153169Y513721D03*
X146870D03*
X150020D03*
X143721Y491674D03*
Y488524D03*
Y485374D03*
X140569Y494823D03*
X134270Y510571D03*
Y504272D03*
X146869Y494823D03*
X153168D03*
X159467D03*
X165768Y488524D03*
X153170Y491674D03*
X150020Y485374D03*
Y482225D03*
X146870Y485374D03*
Y488524D03*
X162618D03*
Y491674D03*
X134272D03*
X165768D03*
X134272Y488524D03*
Y485374D03*
X137421Y491674D03*
Y485374D03*
X140571D03*
X156318Y488523D03*
X156319Y491674D03*
X153169Y485374D03*
Y488524D03*
X159469Y491674D03*
Y488524D03*
Y485374D03*
X150020Y488524D03*
X137421D03*
X165766Y542066D03*
X143721Y532618D03*
X146870Y516870D03*
X150020D03*
X153169D03*
X137421Y535768D03*
Y542066D03*
X134270Y538916D03*
X137421Y532618D03*
X134272Y542066D03*
Y535768D03*
X140570Y535767D03*
X137421Y538918D03*
X153188Y538899D03*
X162617Y535766D03*
X146869Y538954D03*
X146858Y535742D03*
X159449Y542048D03*
Y538898D03*
X159456Y532642D03*
X162617Y542066D03*
Y538916D03*
X149981Y538917D03*
X153132Y535767D03*
X149985Y535771D03*
X153194Y542078D03*
X153187Y532636D03*
X140571Y532618D03*
X143718Y538953D03*
X143686Y542070D03*
X146869Y529469D03*
X134270Y523170D03*
X153168Y529469D03*
X140569D03*
X134270Y516869D03*
X159467Y529469D03*
X134272Y532618D03*
X162618D03*
X165766Y538916D03*
X151989Y552538D03*
X147451Y554136D03*
X142951Y553336D03*
X161280Y553800D03*
Y561700D03*
Y564000D03*
X147451Y551836D03*
Y549536D03*
X142951Y551036D03*
X161280Y566300D03*
X159537Y548256D03*
X147451Y556436D03*
X142951Y555636D03*
X160700Y551356D03*
X151989Y557138D03*
X161280Y556100D03*
X151989Y554838D03*
X161280Y558400D03*
X143968Y614095D03*
X143967Y610945D03*
X137669Y604645D03*
X162865Y595196D03*
Y604645D03*
X156566Y610945D03*
X159716Y598345D03*
X153417Y614095D03*
X150269D03*
X153418Y595197D03*
X162865Y610945D03*
X137661Y614096D03*
X137670Y595197D03*
X147143Y595184D03*
X137669Y610945D03*
Y601495D03*
X140818D03*
X134521Y595196D03*
X134519Y614095D03*
X150269Y598347D03*
X156566Y614095D03*
X143968Y601495D03*
X140821Y614106D03*
X166016Y601496D03*
X159716Y610945D03*
Y614095D03*
Y595197D03*
X166016Y610944D03*
X162867Y614095D03*
X147115Y598360D03*
X150268Y601496D03*
X147141Y614096D03*
X143968Y588898D03*
X153417Y610945D03*
X159716Y604645D03*
X166015Y598345D03*
X147117Y610945D03*
X162865Y601495D03*
X150268Y610944D03*
X159716Y601495D03*
X140818Y610945D03*
X134520Y610944D03*
X153418Y592048D03*
X159716D03*
X134521Y598345D03*
X143968Y592048D03*
X147117Y601495D03*
X143969Y617244D03*
X162881Y617266D03*
X153417Y617244D03*
X150251Y617226D03*
X134521Y617266D03*
X137671D03*
X140821D03*
X156566Y617244D03*
X159716D03*
X150351Y620436D03*
X181514Y479075D03*
X172065Y513721D03*
X175215D03*
X178365Y510571D03*
X175215D03*
X172065D03*
Y501122D03*
X178365Y507422D03*
X175215D03*
Y491674D03*
Y497973D03*
X172065Y491674D03*
X175215Y485374D03*
X175217Y482225D03*
X175215Y501122D03*
X178365D03*
X184664Y485372D03*
X172065Y494823D03*
X178365Y491674D03*
X181514Y488524D03*
X184664Y488522D03*
X175215Y494823D03*
X172065Y497973D03*
X178365Y494823D03*
X172065Y485374D03*
X172067Y482225D03*
X178365Y497973D03*
X172065Y504272D03*
X175216Y504271D03*
X172065Y507422D03*
X178365Y504272D03*
X168916Y510571D03*
Y504272D03*
X178365Y513721D03*
X172065Y488524D03*
X175216Y488523D03*
X178365Y485374D03*
Y488524D03*
X181514Y485374D03*
X178365Y520020D03*
X181514D03*
X172065Y535768D03*
Y526319D03*
X178365Y529469D03*
X175215D03*
X172065D03*
X175215Y523170D03*
X178365D03*
X175216Y535767D03*
X184664Y516869D03*
X172065Y523170D03*
Y520020D03*
X175216Y520019D03*
X168916Y523170D03*
Y516870D03*
X184665Y520019D03*
X178365Y526319D03*
X175215D03*
Y532618D03*
X178365Y535768D03*
X172065Y532618D03*
X175215Y538918D03*
X168916Y535766D03*
X172065Y538918D03*
X168916Y542066D03*
Y538916D03*
X178365Y532618D03*
X874410Y127953D03*
Y139764D03*
Y131890D03*
Y120079D03*
Y124016D03*
Y163386D03*
Y155512D03*
Y147638D03*
Y202755D03*
Y206692D03*
Y194881D03*
Y183071D03*
Y242125D03*
Y238188D03*
Y230314D03*
Y222440D03*
Y214566D03*
Y257873D03*
Y253936D03*
Y249999D03*
Y246062D03*
X894095Y131890D03*
X898032Y139764D03*
Y131890D03*
Y135827D03*
X905906Y127953D03*
X894095Y139764D03*
X905906Y124016D03*
Y120079D03*
Y116142D03*
X901969Y124016D03*
X894095D03*
X890158Y127953D03*
X901969D03*
X898032D03*
X894095D03*
X882284Y139764D03*
X886221Y135827D03*
X882284Y131890D03*
X886221Y124016D03*
X878347D03*
X886221Y127953D03*
X882284D03*
X878347D03*
X901969Y139764D03*
Y135827D03*
Y131890D03*
X886221Y139764D03*
X890158Y135827D03*
X886221Y131890D03*
X890158Y139764D03*
X894095Y135827D03*
X890158Y131890D03*
X878347Y135827D03*
Y116142D03*
X882284Y120079D03*
X886221Y116142D03*
X890158Y120079D03*
X894095Y116142D03*
X898032Y120079D03*
X901969Y116142D03*
X878347Y139764D03*
X882284Y135827D03*
X878347Y131890D03*
Y120079D03*
X882300Y124032D03*
X886221Y120079D03*
X890158Y124016D03*
X894095Y120079D03*
X898032Y124016D03*
X901969Y120079D03*
X905906Y139764D03*
Y135827D03*
Y131890D03*
X894095Y163386D03*
X898032D03*
Y167323D03*
Y171260D03*
Y175197D03*
X901969Y163386D03*
X905906D03*
X898032Y143701D03*
Y147638D03*
Y151575D03*
Y155512D03*
Y159449D03*
X886221Y171260D03*
X901969Y167323D03*
X905906D03*
X901969Y171260D03*
X905906D03*
X901969Y175197D03*
X905906D03*
X890158Y163386D03*
X894095Y167323D03*
Y175197D03*
X905906Y159449D03*
X901969D03*
X894095Y155512D03*
Y147638D03*
X882284Y167323D03*
X886221Y163386D03*
X882284D03*
X878347D03*
X886221Y159449D03*
X882284Y155512D03*
X886221Y151575D03*
X882284Y147638D03*
X886221Y143701D03*
X901969Y147638D03*
Y143701D03*
X890158Y159449D03*
X886221Y155512D03*
X890158Y151575D03*
X886221Y147638D03*
X890158Y143701D03*
X894095Y159449D03*
X890158Y155512D03*
X894095Y151575D03*
X890158Y147638D03*
X894095Y143701D03*
X878347Y159449D03*
Y151575D03*
Y143701D03*
X882284Y159449D03*
X878347Y155512D03*
X882284Y151575D03*
X878347Y147638D03*
X882284Y143701D03*
X905906Y155512D03*
Y151575D03*
Y147638D03*
Y143701D03*
X901969Y155512D03*
Y151575D03*
X898032Y194881D03*
Y198818D03*
Y202755D03*
X894095D03*
X898032Y179134D03*
Y183071D03*
Y190944D03*
X905906Y183071D03*
X901969D03*
Y194881D03*
X905906D03*
X901969Y198818D03*
X905906D03*
X901969Y202755D03*
X905906D03*
X901969Y206692D03*
X905906D03*
X890158Y202755D03*
X898032Y206692D03*
X894095D03*
Y194881D03*
X901969Y179134D03*
X905906D03*
X901969Y190944D03*
X905906D03*
X894095Y183071D03*
X882284Y206692D03*
X886221Y202755D03*
X882284D03*
X878347D03*
X886221Y198818D03*
X882284Y194881D03*
X886221Y190944D03*
Y179134D03*
Y206692D03*
X890158Y198818D03*
X886221Y194881D03*
X890158Y190944D03*
X886221Y183071D03*
X890158Y179134D03*
Y206692D03*
X894095Y198818D03*
X890158Y194881D03*
X894095Y190944D03*
X890158Y183071D03*
X894095Y179134D03*
X878347Y198818D03*
Y190944D03*
Y206692D03*
X882284Y198818D03*
X878347Y194881D03*
X882284Y190944D03*
X878347Y183071D03*
X898032Y238188D03*
X894095D03*
X898032Y234251D03*
Y230314D03*
X905906Y238188D03*
X901969D03*
X898032Y226377D03*
Y222440D03*
Y218503D03*
Y214566D03*
Y210629D03*
X901969Y222440D03*
X905906D03*
X901969Y226377D03*
X905906D03*
Y234251D03*
X901969Y230314D03*
X905906D03*
X901969Y234251D03*
X894095Y222440D03*
X890158Y238188D03*
X894095Y242125D03*
Y230314D03*
X901969Y242125D03*
Y210629D03*
X905906D03*
X901969Y214566D03*
X905906D03*
X901969Y218503D03*
X905906D03*
X894095Y214566D03*
X886221Y226377D03*
X882284Y222440D03*
X886221Y242125D03*
X878347D03*
X886221Y238188D03*
X882284D03*
X878347D03*
X886221Y234251D03*
X882284Y230314D03*
X886221Y218503D03*
X882284Y214566D03*
X886221Y210629D03*
X890158Y234251D03*
X886221Y230314D03*
X890158Y226377D03*
X886221Y222440D03*
X890158Y218503D03*
X886221Y214566D03*
X890158Y210629D03*
X905906Y242125D03*
X898032D03*
X890158D03*
X882284D03*
X894095Y234251D03*
X890158Y230314D03*
X894095Y226377D03*
X890158Y222440D03*
X894095Y218503D03*
X890158Y214566D03*
X894095Y210629D03*
X878347Y234251D03*
Y226377D03*
Y218503D03*
Y210629D03*
X882284Y234251D03*
X878347Y230314D03*
X882284Y226377D03*
X878347Y222440D03*
X882284Y218503D03*
X878347Y214566D03*
X882284Y210629D03*
X901969Y253936D03*
X894095D03*
X890158Y249999D03*
X905906D03*
X898032D03*
X878347Y253936D03*
X886221D03*
X882284Y249999D03*
X905906Y246062D03*
X901969Y249999D03*
X898032Y246062D03*
X894095Y249999D03*
X890158Y246062D03*
X886221Y249999D03*
X882284Y246062D03*
X878347Y249999D03*
X901969Y246062D03*
X894095D03*
X886221D03*
X878347D03*
X905906Y257873D03*
X901969Y261810D03*
X898032Y257873D03*
X894095Y261810D03*
X890158Y257873D03*
X886221Y261810D03*
X882284Y257873D03*
X878347Y261810D03*
X905906Y253936D03*
X901969Y257873D03*
X898032Y253936D03*
X894095Y257873D03*
X890158Y253936D03*
X886221Y257873D03*
X882284Y253936D03*
X878347Y257873D03*
X909843Y131890D03*
X941339Y127953D03*
X913780Y131890D03*
Y127953D03*
Y139764D03*
X921654Y127953D03*
X929528D03*
X937402Y139764D03*
Y127953D03*
X941339Y139764D03*
X933465D03*
X921654Y135827D03*
X941339Y124016D03*
Y120079D03*
Y116142D03*
X937402Y124016D03*
X933465Y127953D03*
X929528Y124016D03*
X925591Y127953D03*
X921654Y124016D03*
X917717Y127953D03*
X909843Y135827D03*
X913780Y124016D03*
X909843Y127953D03*
X921654Y139764D03*
X929528D03*
X925591D03*
X921654Y131890D03*
X941339D03*
Y135827D03*
X933465Y131890D03*
Y135827D03*
X937402Y131890D03*
Y135827D03*
X929528Y131890D03*
Y135827D03*
X925591Y131890D03*
Y135827D03*
X909843Y120079D03*
X913780Y116142D03*
X917717Y120079D03*
X921654Y116142D03*
X925591Y120079D03*
X929528Y116142D03*
X933465Y120079D03*
X937402Y116142D03*
X909843Y124016D03*
X913780Y120079D03*
X917717Y124016D03*
X921654Y120079D03*
X925591Y124016D03*
X929528Y120079D03*
X933465Y124016D03*
X937402Y120079D03*
X913780Y135827D03*
X917717Y139764D03*
Y131890D03*
Y135827D03*
X909843Y139764D03*
X937402Y155512D03*
X941339Y151575D03*
Y155512D03*
X929528Y159449D03*
X913780Y143701D03*
Y159449D03*
X937402Y175197D03*
X941339Y171260D03*
X937402Y167323D03*
X941339Y163386D03*
X929528Y175197D03*
X933465Y171260D03*
X929528Y167323D03*
X933465Y163386D03*
X925591Y171260D03*
X921654Y175197D03*
X925591Y163386D03*
X921654Y167323D03*
X917717Y163386D03*
Y171260D03*
X921654Y159449D03*
X937402D03*
X925591Y151575D03*
X913780Y147638D03*
X917717Y159449D03*
X913780Y155512D03*
Y151575D03*
X941339Y175197D03*
Y167323D03*
X933465Y175197D03*
X937402Y171260D03*
X933465Y167323D03*
X937402Y163386D03*
X929528Y171260D03*
X925591Y175197D03*
X921654Y163386D03*
X925591Y167323D03*
X917717D03*
X921654Y171260D03*
X917717Y175197D03*
X929528Y163386D03*
X941339Y159449D03*
X937402Y151575D03*
X933465Y159449D03*
X925591D03*
X921654Y147638D03*
X909843Y163386D03*
X913780D03*
X909843Y167323D03*
X913780D03*
X909843Y171260D03*
X913780D03*
X909843Y175197D03*
X913780D03*
X909843Y147638D03*
X933465Y151575D03*
Y155512D03*
X921654Y151575D03*
X929528D03*
Y155512D03*
X925591Y143701D03*
Y147638D03*
Y155512D03*
X909843Y159449D03*
Y143701D03*
Y155512D03*
X941339Y143701D03*
Y147638D03*
X933465Y143701D03*
Y147638D03*
X937402Y143701D03*
Y147638D03*
X929528Y143701D03*
Y147638D03*
X917717Y155512D03*
Y151575D03*
Y143701D03*
Y147638D03*
X921654Y155512D03*
X917717Y179134D03*
X913780Y183071D03*
X921654Y194881D03*
X917717Y198818D03*
X937402Y194881D03*
X933465Y198818D03*
X929528Y202755D03*
X925591Y206692D03*
X929528Y194881D03*
X925591Y198818D03*
X921654Y202755D03*
X917717Y206692D03*
X933465D03*
X937402Y202755D03*
X941339Y198818D03*
Y206692D03*
X925591Y190944D03*
X933465Y179134D03*
X929528Y183071D03*
X925591Y179134D03*
X921654Y183071D03*
X941339Y190944D03*
X933465D03*
X937402Y183071D03*
X941339Y179134D03*
X917717Y190944D03*
X925591Y194881D03*
X921654Y198818D03*
X917717Y202755D03*
X937402Y206692D03*
X941339Y202755D03*
Y194881D03*
X937402Y198818D03*
X933465Y202755D03*
X929528Y206692D03*
X933465Y194881D03*
X929528Y198818D03*
X925591Y202755D03*
X921654Y206692D03*
X917717Y194881D03*
X937402Y179134D03*
X933465Y183071D03*
X929528Y190944D03*
Y179134D03*
X925591Y183071D03*
X921654Y179134D03*
X937402Y190944D03*
X917717Y183071D03*
X921654Y190944D03*
X909843Y194881D03*
X913780D03*
X909843Y198818D03*
X913780D03*
X909843Y202755D03*
X913780D03*
X909843Y206692D03*
X913780D03*
X909843Y179134D03*
X913780D03*
X909843Y183071D03*
Y190944D03*
X913780D03*
X921654Y238188D03*
X917717D03*
Y214566D03*
X913780Y238188D03*
X909843D03*
X913780Y214566D03*
X941339Y226377D03*
X937402Y222440D03*
X933465Y226377D03*
X929528Y222440D03*
X925591Y226377D03*
X929528Y230314D03*
X937402D03*
X941339Y234251D03*
X937402Y238188D03*
X933465Y234251D03*
X929528Y238188D03*
X925591Y234251D03*
X921654Y210629D03*
X925591Y214566D03*
X929528Y210629D03*
X941339Y214566D03*
X933465D03*
X937402Y210629D03*
X917717Y222440D03*
Y226377D03*
X921654Y222440D03*
Y226377D03*
X917717Y230314D03*
Y234251D03*
X921654Y230314D03*
Y234251D03*
X925591Y230314D03*
Y222440D03*
X933465D03*
X941339D03*
X937402Y226377D03*
X929528D03*
X941339Y238188D03*
Y230314D03*
X937402Y242125D03*
Y234251D03*
X933465Y238188D03*
Y230314D03*
X929528Y242125D03*
Y234251D03*
X925591Y238188D03*
X921654Y242125D03*
X929528Y214566D03*
X933465Y210629D03*
X925591D03*
X917717D03*
X921654Y218503D03*
X925591D03*
X929528D03*
X933465D03*
X937402D03*
X941339D03*
X921654Y214566D03*
X917717Y218503D03*
X937402Y214566D03*
X913780Y226377D03*
X909843Y222440D03*
X913780D03*
X909843Y226377D03*
Y230314D03*
Y234251D03*
X913780Y230314D03*
Y234251D03*
Y242125D03*
X909843D03*
Y214566D03*
Y210629D03*
X913780D03*
X909843Y218503D03*
X913780D03*
X941339Y242125D03*
X933465D03*
X925591D03*
X917717D03*
X937402Y253936D03*
X929528D03*
X921654D03*
X941339Y249999D03*
X933465D03*
X925591D03*
X917717D03*
X913780Y253936D03*
X909843Y261810D03*
Y257873D03*
Y253936D03*
Y249999D03*
Y246062D03*
X941339D03*
X937402Y249999D03*
X933465Y246062D03*
X929528Y249999D03*
X925591Y246062D03*
X921654Y249999D03*
X917717Y246062D03*
X913780Y249999D03*
X937402Y246062D03*
X929528D03*
X921654D03*
X913780D03*
X941339Y257873D03*
X937402Y261810D03*
X933465Y257873D03*
X929528Y261810D03*
X925591Y257873D03*
X921654Y261810D03*
X917717Y257873D03*
X913780Y261810D03*
X941339Y253936D03*
X937402Y257873D03*
X933465Y253936D03*
X929528Y257873D03*
X925591Y253936D03*
X921654Y257873D03*
X917717Y253936D03*
X913780Y257873D03*
X953149Y127953D03*
X949212D03*
Y139764D03*
X957086Y127953D03*
X964960D03*
X972834D03*
X957086Y139764D03*
X953149Y135827D03*
X968897Y139764D03*
X953149Y124016D03*
Y120079D03*
Y116142D03*
X972834Y124016D03*
X968897Y127953D03*
X964960Y124016D03*
X961023Y127953D03*
X957086Y124016D03*
X972834Y139764D03*
X953149D03*
Y131890D03*
X957086D03*
X964960D03*
X961023Y139764D03*
Y131890D03*
Y135827D03*
X957086D03*
Y116142D03*
X961023Y120079D03*
X964960Y116142D03*
X968897Y120079D03*
X972834Y116142D03*
X957086Y120079D03*
X961023Y124016D03*
X964960Y120079D03*
X968897Y124016D03*
X972834Y120079D03*
Y135827D03*
Y131890D03*
X964960Y135827D03*
Y139764D03*
X968897Y135827D03*
Y131890D03*
X949212Y155512D03*
X953149Y163386D03*
X949212Y167323D03*
X964960D03*
X968897Y163386D03*
X957086Y175197D03*
X961023Y171260D03*
X953149D03*
X949212Y175197D03*
X961023Y163386D03*
X957086Y167323D03*
X972834D03*
X968897Y171260D03*
X964960Y175197D03*
X972834D03*
X968897Y151575D03*
X964960Y159449D03*
X957086D03*
X953149Y151575D03*
X949212Y159449D03*
X972834D03*
X953149Y167323D03*
X957086Y163386D03*
X949212Y171260D03*
Y163386D03*
X972834Y171260D03*
X968897Y175197D03*
X972834Y163386D03*
X968897Y167323D03*
X964960Y171260D03*
X961023Y175197D03*
Y167323D03*
X964960Y163386D03*
X953149Y175197D03*
X957086Y171260D03*
X953149Y159449D03*
X949212Y151575D03*
X972834Y147638D03*
X968897Y159449D03*
X961023D03*
Y147638D03*
X972834Y151575D03*
X957086Y143701D03*
X961023D03*
X957086Y151575D03*
Y147638D03*
Y155512D03*
X953149Y143701D03*
Y155512D03*
X949212Y143701D03*
Y147638D03*
X964960Y143701D03*
X961023Y155512D03*
Y151575D03*
X964960Y155512D03*
Y151575D03*
X968897Y155512D03*
X964960Y147638D03*
X968897D03*
Y143701D03*
X972834D03*
Y155512D03*
X949212Y194881D03*
X968897Y198818D03*
X964960Y202755D03*
X961023Y206692D03*
X972834Y194881D03*
X953149Y206692D03*
X964960Y194881D03*
X961023Y198818D03*
X957086Y202755D03*
X949212D03*
X953149Y198818D03*
X957086Y194881D03*
X972834Y202755D03*
X968897Y206692D03*
X949212Y183071D03*
X953149Y179134D03*
X961023D03*
X957086Y183071D03*
X953149Y190944D03*
X968897D03*
X972834Y183071D03*
X961023Y190944D03*
X964960Y183071D03*
X968897Y179134D03*
X964960Y198818D03*
X961023Y202755D03*
X957086Y206692D03*
X968897Y194881D03*
X953149D03*
X949212Y198818D03*
Y206692D03*
X953149Y202755D03*
X961023Y194881D03*
X957086Y198818D03*
X972834Y206692D03*
Y198818D03*
X968897Y202755D03*
X964960Y206692D03*
X972834Y190944D03*
X964960Y179134D03*
X961023Y183071D03*
X957086Y190944D03*
X953149Y183071D03*
X957086Y179134D03*
X949212D03*
X964960Y190944D03*
X968897Y183071D03*
X972834Y179134D03*
Y238188D03*
X968897Y226377D03*
Y234251D03*
X953149Y226377D03*
X949212Y222440D03*
Y230314D03*
X964960Y222440D03*
X961023Y226377D03*
X957086Y222440D03*
X964960Y230314D03*
X957086D03*
X953149Y234251D03*
X949212Y238188D03*
X964960D03*
X961023Y234251D03*
X957086Y238188D03*
X953149Y214566D03*
X957086Y210629D03*
X949212D03*
X972834D03*
X968897Y214566D03*
X961023D03*
X964960Y210629D03*
X972834Y222440D03*
Y226377D03*
Y230314D03*
Y234251D03*
X968897Y230314D03*
Y222440D03*
X953149D03*
X961023D03*
X972834Y242125D03*
X949212Y226377D03*
X964960D03*
X957086D03*
X953149Y238188D03*
Y230314D03*
X949212Y242125D03*
Y234251D03*
X968897Y238188D03*
X964960Y242125D03*
Y234251D03*
X961023Y238188D03*
Y230314D03*
X957086Y242125D03*
Y234251D03*
X949212Y214566D03*
X953149Y210629D03*
X968897D03*
X964960Y214566D03*
X972834Y218503D03*
X949212D03*
X953149D03*
X957086Y214566D03*
X961023Y210629D03*
X972834Y214566D03*
X957086Y218503D03*
X961023D03*
X964960D03*
X968897D03*
Y242125D03*
X961023D03*
X953149D03*
X972834Y253936D03*
X949212Y261810D03*
Y257873D03*
Y253936D03*
X964960D03*
X957086D03*
X953149Y249999D03*
X949212D03*
Y246062D03*
X968897Y249999D03*
X961023D03*
X972834D03*
X968897Y246062D03*
X964960Y249999D03*
X961023Y246062D03*
X957086Y249999D03*
X953149Y246062D03*
X972834D03*
X964960D03*
X957086D03*
X972834Y261810D03*
X968897Y257873D03*
X964960Y261810D03*
X961023Y257873D03*
X957086Y261810D03*
X953149Y257873D03*
X972834D03*
X968897Y253936D03*
X964960Y257873D03*
X961023Y253936D03*
X957086Y257873D03*
X953149Y253936D03*
X992519Y139764D03*
X996456D03*
Y131890D03*
Y135827D03*
X1000393Y131890D03*
X980708Y127953D03*
Y139764D03*
X1008267Y135827D03*
Y127953D03*
Y124016D03*
X984645Y135827D03*
X1000393Y139764D03*
X992519Y127953D03*
Y124016D03*
X988582Y127953D03*
Y124016D03*
Y120079D03*
Y116142D03*
X984645Y127953D03*
X980708Y124016D03*
X996456Y127953D03*
X1000393Y124016D03*
Y127953D03*
X1004330D03*
X976771D03*
X980708Y135827D03*
Y131890D03*
X1008267Y139764D03*
X976771Y120079D03*
X980708Y116142D03*
X984645Y120079D03*
X1008267Y131890D03*
X1004330Y135827D03*
Y139764D03*
X976771Y124016D03*
X980708Y120079D03*
X984645Y124016D03*
X1004330Y131890D03*
X1000393Y135827D03*
X992519Y115742D03*
X996456Y120079D03*
X1000393Y116142D03*
X1004330Y120079D03*
X1008267Y116142D03*
X992519Y120079D03*
X996456Y124016D03*
X1000393Y120079D03*
X1004330Y124016D03*
X1008267Y120079D03*
X988582Y139764D03*
Y135827D03*
X984645Y131890D03*
X976771D03*
Y139764D03*
X988582Y131890D03*
X984645Y139764D03*
X976771Y135827D03*
X996456Y163386D03*
X1000393D03*
X996456Y167323D03*
Y171260D03*
Y175197D03*
X992519Y163386D03*
X988582D03*
X980708Y175197D03*
X996456Y143701D03*
Y147638D03*
Y151575D03*
Y155512D03*
Y159449D03*
X976771Y163386D03*
Y171260D03*
X1008267Y163386D03*
Y171260D03*
Y159449D03*
Y143701D03*
Y151575D03*
X980708Y163386D03*
X984645D03*
X988582Y167323D03*
X992519D03*
X980708D03*
X984645D03*
X988582Y171260D03*
X992519D03*
X980708D03*
X984645D03*
X988582Y175197D03*
X992519D03*
X984645D03*
X1000393Y167323D03*
X1004330Y163386D03*
X1000393Y175197D03*
X988582Y159449D03*
X992519D03*
X984645Y147638D03*
X1000393D03*
Y155512D03*
X976771Y167323D03*
Y175197D03*
X980708Y159449D03*
Y155512D03*
X976771Y151575D03*
X1004330Y143701D03*
X1008267Y147638D03*
X1004330Y151575D03*
X1008267Y155512D03*
X1004330Y159449D03*
X1008267Y167323D03*
X1004330Y171260D03*
X1008267Y175197D03*
X1000393Y143701D03*
X1004330Y147638D03*
X1000393Y151575D03*
X1004330Y155512D03*
X1000393Y159449D03*
X1004330Y167323D03*
X1000393Y171260D03*
X1004330Y175197D03*
X988582Y147638D03*
Y143701D03*
X984645Y155512D03*
Y151575D03*
Y143701D03*
X988582Y151575D03*
X976771Y147638D03*
X980708Y143701D03*
X976771Y155512D03*
X980708Y147638D03*
Y151575D03*
X976771Y159449D03*
Y143701D03*
X996456Y194881D03*
Y198818D03*
Y202755D03*
X1000393D03*
X996456Y179134D03*
Y183071D03*
Y190944D03*
X992519Y183071D03*
X988582D03*
X976771Y179134D03*
X980708Y183071D03*
X976771Y206692D03*
Y198818D03*
Y190944D03*
X1008267Y202755D03*
Y198818D03*
Y190944D03*
Y179134D03*
X980708Y198818D03*
X988582Y194881D03*
X992519D03*
X980708D03*
X984645D03*
X988582Y198818D03*
X992519D03*
X984645D03*
X988582Y202755D03*
X992519D03*
X980708D03*
X984645D03*
X988582Y206692D03*
X992519D03*
X980708D03*
X984645D03*
X1000393D03*
X996456D03*
X1004330Y202755D03*
X1000393Y194881D03*
X988582Y179134D03*
X992519D03*
X988582Y190944D03*
X992519D03*
X980708D03*
X984645D03*
X980708Y179134D03*
X984645D03*
Y183071D03*
X1000393D03*
X976771Y202755D03*
Y194881D03*
Y183071D03*
X1004330Y179134D03*
X1008267Y183071D03*
X1004330Y190944D03*
X1008267Y194881D03*
X1004330Y198818D03*
X1008267Y206692D03*
X1000393Y179134D03*
X1004330Y183071D03*
X1000393Y190944D03*
X1004330Y194881D03*
X1000393Y198818D03*
X1004330Y206692D03*
X992519Y238188D03*
X988582D03*
X984645D03*
X980708D03*
X1000393D03*
X996456D03*
Y234251D03*
Y230314D03*
Y226377D03*
Y222440D03*
Y218503D03*
Y214566D03*
Y210629D03*
X976771Y238188D03*
Y214566D03*
X980708D03*
X1008267Y226377D03*
Y242125D03*
Y238188D03*
Y234251D03*
Y218503D03*
Y210629D03*
X1000393Y222440D03*
X988582D03*
X992519D03*
X980708D03*
X984645D03*
X988582Y226377D03*
X992519D03*
X984645D03*
X980708D03*
X988582Y230314D03*
X992519D03*
Y234251D03*
X980708Y230314D03*
Y234251D03*
X984645Y230314D03*
Y234251D03*
X988582D03*
X1000393Y230314D03*
X1004330Y238188D03*
X1000393Y242125D03*
X980708D03*
X984645D03*
X992519D03*
X984645Y214566D03*
X988582Y210629D03*
X992519D03*
X980708D03*
X984645D03*
X988582Y214566D03*
X992519D03*
X988582Y218503D03*
X992519D03*
X980708D03*
X984645D03*
X1000393Y214566D03*
X976771Y222440D03*
Y226377D03*
Y230314D03*
Y234251D03*
Y210629D03*
Y218503D03*
X1004330Y210629D03*
X1008267Y214566D03*
X1004330Y218503D03*
X1008267Y222440D03*
X1004330Y226377D03*
X1008267Y230314D03*
X1004330Y234251D03*
X1000393Y210629D03*
X1004330Y214566D03*
X1000393Y218503D03*
X1004330Y222440D03*
X1000393Y226377D03*
X1004330Y230314D03*
X1000393Y234251D03*
X1004330Y242125D03*
X996456D03*
X988582D03*
X976771D03*
X1008267Y253936D03*
X980708D03*
X984645D03*
Y257873D03*
Y261810D03*
X992519Y253936D03*
X1000393D03*
X984645Y246062D03*
Y249999D03*
X988582D03*
X996456D03*
X1004330D03*
X976771D03*
X1008267D03*
X1004330Y246062D03*
X1000393Y249999D03*
X996456Y246062D03*
X992519Y249999D03*
X988582Y246062D03*
X980708Y249999D03*
X976771Y246062D03*
X1008267D03*
X1000393D03*
X992519D03*
X980708D03*
X1008267Y261810D03*
X1004330Y257873D03*
X1000393Y261810D03*
X996456Y257873D03*
X992519Y261810D03*
X988582Y257873D03*
X980708Y261810D03*
X976771Y257873D03*
X1008267D03*
X1004330Y253936D03*
X1000393Y257873D03*
X996456Y253936D03*
X992519Y257873D03*
X988582Y253936D03*
X980708Y257873D03*
X976771Y253936D03*
X1021751Y117469D03*
X1012204Y131890D03*
Y139764D03*
Y127953D03*
X1016141Y124016D03*
X1020078Y127953D03*
X1016141D03*
X1020078Y139764D03*
X1012204Y120079D03*
X1016141Y116142D03*
X1020078Y120079D03*
Y131890D03*
X1016141Y135827D03*
Y139764D03*
X1012204Y124016D03*
X1016141Y120079D03*
X1023278D03*
X1016141Y131890D03*
X1012204Y135827D03*
Y167323D03*
Y163386D03*
X1016141D03*
X1020078D03*
X1012204Y175197D03*
Y147638D03*
Y155512D03*
X1016141Y143701D03*
X1020078Y147638D03*
X1016141Y151575D03*
X1020078Y155512D03*
X1016141Y159449D03*
X1020078Y167323D03*
X1016141Y171260D03*
X1020078Y175197D03*
X1012204Y143701D03*
X1016141Y147638D03*
X1012204Y151575D03*
X1016141Y155512D03*
X1012204Y159449D03*
X1016141Y167323D03*
X1012204Y171260D03*
X1016141Y175197D03*
X1012204Y206692D03*
Y202755D03*
Y194881D03*
X1016141Y202755D03*
X1020078D03*
X1012204Y183071D03*
X1016141Y179134D03*
X1020078Y183071D03*
X1016141Y190944D03*
X1020078Y194881D03*
X1016141Y198818D03*
X1020078Y206692D03*
X1012204Y179134D03*
X1016141Y183071D03*
X1012204Y190944D03*
X1016141Y194881D03*
X1012204Y198818D03*
X1016141Y206692D03*
X1012204Y222440D03*
Y238188D03*
Y230314D03*
X1016141Y242125D03*
X1020078D03*
X1016141Y238188D03*
X1020078D03*
X1012204Y214566D03*
Y242125D03*
X1016141Y210629D03*
X1020078Y214566D03*
X1016141Y218503D03*
X1020078Y222440D03*
X1016141Y226377D03*
X1020078Y230314D03*
X1016141Y234251D03*
X1012204Y210629D03*
X1016141Y214566D03*
X1012204Y218503D03*
X1016141Y222440D03*
X1012204Y226377D03*
X1016141Y230314D03*
X1012204Y234251D03*
X1020078Y257873D03*
X1016141Y253936D03*
X1020078D03*
X1012204Y249999D03*
X1020078D03*
Y246062D03*
X1016141Y249999D03*
X1012204Y246062D03*
X1016141D03*
Y261810D03*
X1012204Y257873D03*
X1016141D03*
X1012204Y253936D03*
X1708976Y884006D03*
G54D32*
X943111Y5908D03*
X935236D03*
X927361D03*
X919486D03*
X911616D03*
X943111Y13778D03*
X935236D03*
X927361D03*
X919486D03*
X911616D03*
X958856Y5908D03*
X950986D03*
X958856Y13778D03*
X950986D03*
X1708976Y687306D03*
G54D14*
X39370Y801181D03*
X1360630Y135826D03*
Y801181D03*
X1708976Y406306D03*
G54D23*
X108200Y775800D03*
X112700Y775300D03*
Y770800D03*
X108200D03*
X103700D03*
Y775800D03*
Y766300D03*
X108200D03*
X112700D03*
X158170Y314302D03*
X162670D03*
X153670D03*
X156170Y318302D03*
X160670D03*
X224500Y170500D03*
Y174700D03*
Y166300D03*
Y178900D03*
X223000Y184000D03*
Y188500D03*
X225000Y192500D03*
X229200D03*
X259500Y138500D03*
X261500Y173500D03*
X253000Y166500D03*
X258700D03*
X262900D03*
X243000Y176500D03*
X243500Y166500D03*
Y162000D03*
Y157000D03*
X261500Y179000D03*
Y184500D03*
X261000Y190500D03*
X258225Y193963D03*
X266500Y184500D03*
Y190500D03*
X243000Y181000D03*
Y186000D03*
X239900Y600100D03*
X240000Y608600D03*
Y604400D03*
X271000Y184500D03*
X329500Y192500D03*
X328000Y197400D03*
X334500Y197500D03*
Y192500D03*
X344000Y197500D03*
X339500D03*
X344000Y192500D03*
X339500D03*
X536081Y304376D03*
X536809Y298789D03*
X565063Y256608D03*
Y247608D03*
Y252108D03*
X560318Y267199D03*
Y272199D03*
X560418Y278299D03*
Y283799D03*
Y289299D03*
X560318Y295699D03*
X553563Y306108D03*
Y310608D03*
X557904Y327115D03*
X562123Y319158D03*
X553455Y314807D03*
X553463Y319108D03*
X557863D03*
X605063Y257608D03*
X585515Y276459D03*
X583009Y264117D03*
X585351Y269292D03*
X587984Y246148D03*
X587980Y251975D03*
X589164Y264150D03*
X582738Y273300D03*
X587063Y257608D03*
X582976Y246148D03*
X583286Y251974D03*
X582682Y257614D03*
X589400Y308626D03*
X585737Y289608D03*
Y283108D03*
X582683Y279618D03*
X582411Y286589D03*
X582363Y293408D03*
X580563Y308608D03*
X583391Y298870D03*
X583282Y303091D03*
X611563Y278108D03*
X607563Y265608D03*
X607463Y270608D03*
X607563Y261108D03*
X609063Y255608D03*
X607563Y276108D03*
Y282108D03*
Y287608D03*
Y293608D03*
X607519Y299497D03*
X611563Y290108D03*
Y284608D03*
X666593Y226677D03*
X662593Y223677D03*
X658093D03*
X670063Y274708D03*
X669633Y259148D03*
X672100Y299800D03*
X704537Y221492D03*
X678063Y238108D03*
X673063D03*
X672927Y219677D03*
X677927D03*
X686063Y230108D03*
X696800Y237900D03*
X682763Y238008D03*
X686063Y224608D03*
X703600Y233700D03*
X687253Y237878D03*
X691753D03*
X698300Y226500D03*
X693800D03*
X689623Y269648D03*
X694963Y269608D03*
X689723Y274748D03*
X694223D03*
X679723D03*
X684223D03*
X690233Y255748D03*
X695000Y255800D03*
X690133Y260348D03*
X694633D03*
X680133Y259148D03*
X684633D03*
X674563Y274708D03*
X674133Y259148D03*
X695963Y302308D03*
Y297808D03*
Y293308D03*
X690663Y287608D03*
Y292108D03*
X677000Y299900D03*
X682063Y299108D03*
X683800Y295000D03*
X684063Y285908D03*
Y290408D03*
X712337Y207792D03*
X712137Y213292D03*
Y219392D03*
X725300Y228700D03*
X730300D03*
X711300D03*
X716300D03*
X716900Y233800D03*
X721400D03*
X730400D03*
X725900D03*
X735400D03*
X707900D03*
X712400D03*
X738800Y272000D03*
Y265500D03*
Y258000D03*
Y251500D03*
X706800Y272500D03*
Y265500D03*
Y258000D03*
Y252000D03*
X715300Y272000D03*
Y265500D03*
Y258000D03*
Y251500D03*
X724300Y272000D03*
Y265500D03*
Y258000D03*
Y251500D03*
X732300Y272000D03*
Y265500D03*
Y258000D03*
Y251500D03*
X706800Y290700D03*
X718800Y291000D03*
X714300D03*
X707363Y298108D03*
X718863Y295908D03*
X714363D03*
X723300Y291000D03*
X732300D03*
X727800D03*
X723363Y295908D03*
X732363D03*
X727863D03*
X737300Y291000D03*
X921300Y74700D03*
X918100Y71900D03*
X929464Y49420D03*
X925022Y42909D03*
X929713Y44849D03*
X926500Y60050D03*
X930500Y57500D03*
X976066Y26581D03*
X971466Y26681D03*
X975086Y61900D03*
X970000Y61050D03*
X985880Y41686D03*
X980566Y26581D03*
X985880Y46086D03*
Y50586D03*
X1177600Y241200D03*
X1173400D03*
X1166400Y234300D03*
X1170600D03*
X1175700D03*
X1171300Y215700D03*
X1166300D03*
X1175999D03*
X1177200Y248200D03*
X1173000D03*
X1177300Y254400D03*
X1173100D03*
X1176300Y261500D03*
X1171200D03*
X1167000D03*
X1168000Y280000D03*
X1173000D03*
X1177500D03*
X1203100Y241100D03*
X1198900D03*
X1207900D03*
X1182400Y241200D03*
X1197900Y234300D03*
X1207400D03*
X1203200D03*
X1179900D03*
X1188900D03*
X1184700D03*
X1193700D03*
X1190300Y215700D03*
X1185300D03*
X1208800D03*
X1203800D03*
X1180601D03*
X1199300D03*
X1194500D03*
X1182000Y248200D03*
X1202600Y254100D03*
X1198400D03*
X1207400D03*
X1202500Y247500D03*
X1198300D03*
X1207300D03*
X1182100Y254400D03*
X1203800Y261500D03*
X1208000D03*
X1194300D03*
X1198500D03*
X1185300D03*
X1189500D03*
X1180500D03*
X1187000Y280000D03*
X1192000D03*
X1205500D03*
X1210500D03*
X1182500D03*
X1201000D03*
X1196200D03*
X1229000Y210500D03*
X1242500Y209000D03*
X1232000Y194500D03*
X1237000D03*
X1226500Y201500D03*
Y194500D03*
X1244500D03*
X1212900Y234300D03*
X1214800Y215700D03*
X1233900Y240700D03*
X1239900D03*
X1244900D03*
X1228900D03*
X1228500Y235000D03*
X1234000D03*
X1240000D03*
X1245000D03*
X1214000Y261500D03*
X1233800Y246600D03*
X1239800D03*
X1244800D03*
X1228800D03*
X1229000Y252000D03*
X1245000D03*
X1240000D03*
X1234000D03*
X1227000Y279000D03*
X1242000D03*
X1232000Y292000D03*
X1237000D03*
X1227000Y285500D03*
X1244500Y292000D03*
X1247500Y209000D03*
X1252500Y194500D03*
X1263000Y210307D03*
X1257500Y194500D03*
X1263000Y202000D03*
X1262500Y194500D03*
X1255900Y240700D03*
X1249900D03*
X1262500Y235000D03*
X1250000D03*
X1256000D03*
X1255800Y246600D03*
X1249800D03*
X1262000Y252000D03*
X1256000D03*
X1250000D03*
X1247000Y279000D03*
X1262500Y279500D03*
X1252000Y292000D03*
X1257000D03*
X1262500Y286000D03*
X1327782Y192579D03*
Y200579D03*
Y207579D03*
X1328411Y237679D03*
X1327782Y215579D03*
Y221579D03*
X1327841Y228639D03*
X1332683Y240409D03*
X1328356Y242091D03*
X1328317Y246291D03*
X1332683Y244609D03*
Y248809D03*
X1326250Y669550D03*
X1366672Y210312D03*
X1360844Y210366D03*
X1355944Y210313D03*
X1351525Y207104D03*
X1351545Y202879D03*
Y198575D03*
X1378115Y189144D03*
X1374000Y192500D03*
Y188300D03*
Y196700D03*
X1378500Y198000D03*
X1378115Y193344D03*
X1375196Y217203D03*
X1367042Y223895D03*
X1375359Y230110D03*
X1372000Y240500D03*
X1351777Y227823D03*
X1360644Y223881D03*
X1350987Y236754D03*
X1351668Y232125D03*
X1355644Y223881D03*
X1351899Y219598D03*
X1351954Y215268D03*
X1354989Y239016D03*
X1350950Y241000D03*
X1349639Y211374D03*
X1349298Y223737D03*
X1372000Y245300D03*
Y249500D03*
X1355050Y247300D03*
X1350950Y246100D03*
X1382500Y193500D03*
Y188000D03*
X1708976Y771606D03*
G54D24*
X193900Y274372D03*
X183900D03*
X213900D03*
X203900D03*
X302500Y207200D03*
X292500D03*
X326200D03*
X336200D03*
X312500D03*
X346200D03*
X465485Y200680D03*
Y190680D03*
Y180680D03*
X488462Y180761D03*
Y190761D03*
Y200761D03*
X501742Y215594D03*
X511742D03*
X521742D03*
X531742D03*
X772300Y16200D03*
X762300D03*
X752300D03*
X785300Y16100D03*
X795300D03*
X805300D03*
X819291Y265354D03*
Y285354D03*
X1075197Y92126D03*
Y112126D03*
X1348785Y161642D03*
X1323195D03*
X1348785Y179358D03*
X1323195D03*
X1708976Y603006D03*
G54D33*
X1027722Y-9125D03*
X1054494D03*
X1708976Y322006D03*
G54D15*
X42587Y151614D03*
X80579D03*
X1708976Y237706D03*
G54D34*
G01X127746Y-260199D02*
X95746D01*
G01X127746Y-276199D02*
Y-356199D01*
G01D02*
X1310146D01*
G01X127746Y-311699D02*
X1310146D01*
G01X123746Y-260199D02*
G02I-12000J0D01*
G01X118596D02*
G02I-6850J0D01*
G01X111746Y-276199D02*
Y-244199D01*
G01X127746Y-276199D02*
X1310146D01*
G01X522646D02*
Y-356199D01*
G01X660146Y-276199D02*
Y-356199D01*
G01X775146Y-276199D02*
Y-356199D01*
G01X942646Y-276199D02*
Y-356199D01*
G01X1112646Y-276199D02*
Y-356199D01*
G01X1310146Y-276199D02*
Y-356199D01*
G01X1342146Y-260199D02*
X1310146D01*
G01X1338146D02*
G02I-12000J0D01*
G01X1332996D02*
G02I-6850J0D01*
G01X1326146Y-276199D02*
Y-244199D01*
G54D16*
X41603Y177598D03*
X65579D03*
X57587D03*
X49595D03*
X45559Y187598D03*
X37567D03*
X53551D03*
X73571Y177598D03*
X81563D03*
X77607Y187598D03*
X69615D03*
X85599D03*
X1708976Y659206D03*
G54D25*
X336417Y21260D03*
X293110Y55906D03*
X336417Y90551D03*
X789850Y236220D03*
Y283464D03*
X1376968Y21260D03*
X1333661Y55906D03*
X1376968Y90551D03*
X1708976Y434406D03*
G54D35*
G01X145579Y-328699D02*
Y-346199D01*
X154313D01*
G01X167446Y-334533D02*
Y-346199D01*
G01Y-329866D02*
X167009Y-329574D01*
Y-328991D01*
X167446Y-328699D01*
X167883Y-328991D01*
Y-329574D01*
X167446Y-329866D01*
G01X181889Y-350574D02*
X183418Y-351741D01*
X185164Y-352032D01*
X186692Y-351741D01*
X188003Y-350283D01*
X188876Y-348241D01*
Y-334533D01*
G01Y-336866D02*
X188003Y-335699D01*
X186692Y-334824D01*
X185164Y-334533D01*
X183418Y-335116D01*
X182326Y-336282D01*
X181452Y-338324D01*
X181016Y-340366D01*
X181234Y-342116D01*
X182108Y-344158D01*
X183418Y-345616D01*
X185164Y-346199D01*
X186474Y-345907D01*
X188003Y-344741D01*
X188876Y-343575D01*
G01X198734Y-346199D02*
Y-328699D01*
G01Y-337157D02*
X199826Y-335699D01*
X200918Y-334824D01*
X202664Y-334533D01*
X203974Y-334824D01*
X205503Y-335991D01*
X206158Y-337741D01*
Y-346199D01*
G01X219946Y-328699D02*
Y-346199D01*
G01X216889Y-334533D02*
X223003D01*
G01X233734Y-346199D02*
Y-334533D01*
G01Y-337449D02*
X234608Y-335991D01*
X235918Y-334824D01*
X237664Y-334533D01*
X239192Y-334824D01*
X240503Y-335991D01*
X241158Y-338032D01*
Y-346199D01*
G01X254946Y-334533D02*
Y-346199D01*
G01Y-329866D02*
X254509Y-329574D01*
Y-328991D01*
X254946Y-328699D01*
X255383Y-328991D01*
Y-329574D01*
X254946Y-329866D01*
G01X268734Y-346199D02*
Y-334533D01*
G01Y-337449D02*
X269608Y-335991D01*
X270918Y-334824D01*
X272664Y-334533D01*
X274192Y-334824D01*
X275503Y-335991D01*
X276158Y-338032D01*
Y-346199D01*
G01X286889Y-350574D02*
X288418Y-351741D01*
X290164Y-352032D01*
X291692Y-351741D01*
X293003Y-350283D01*
X293876Y-348241D01*
Y-334533D01*
G01Y-336866D02*
X293003Y-335699D01*
X291692Y-334824D01*
X290164Y-334533D01*
X288418Y-335116D01*
X287326Y-336282D01*
X286452Y-338324D01*
X286016Y-340366D01*
X286234Y-342116D01*
X287108Y-344158D01*
X288418Y-345616D01*
X290164Y-346199D01*
X291474Y-345907D01*
X293003Y-344741D01*
X293876Y-343575D01*
G01X320579Y-346199D02*
Y-328699D01*
X325819D01*
X327566Y-329574D01*
X328876Y-331616D01*
X329313Y-333949D01*
X328876Y-336282D01*
X327784Y-338032D01*
X325819Y-338908D01*
X320579D01*
G01X346813Y-346199D02*
X338079D01*
Y-328699D01*
X346813D01*
G01X343319Y-337157D02*
X338079D01*
G01X361692Y-336866D02*
X362566Y-335991D01*
X363221Y-334533D01*
X363658Y-332490D01*
X363221Y-330741D01*
X362348Y-329574D01*
X360819Y-328699D01*
X354924D01*
Y-346199D01*
X362129D01*
X363658Y-345033D01*
X364531Y-343282D01*
X364968Y-341241D01*
X364531Y-339199D01*
X363221Y-337449D01*
X361692Y-336866D01*
X354924D01*
G01X390579Y-346199D02*
Y-328699D01*
X395819D01*
X397566Y-329574D01*
X398876Y-331616D01*
X399313Y-333949D01*
X398876Y-336282D01*
X397784Y-338032D01*
X395819Y-338908D01*
X390579D01*
G01X406769Y-346199D02*
Y-328699D01*
X412446Y-343282D01*
X418123Y-328699D01*
Y-346199D01*
G01X434749Y-330158D02*
X433439Y-329282D01*
X431911Y-328699D01*
X430164D01*
X428199Y-329574D01*
X426671Y-331032D01*
X425579Y-332783D01*
X424706Y-335699D01*
X424487Y-338324D01*
X424924Y-340949D01*
X425579Y-342699D01*
X426889Y-344449D01*
X428418Y-345616D01*
X429946Y-346199D01*
X431474D01*
X433003Y-345616D01*
X434313Y-344741D01*
X435405Y-343575D01*
G01X460579Y-346199D02*
Y-328699D01*
X465819D01*
X467566Y-329574D01*
X468876Y-331616D01*
X469313Y-333949D01*
X468876Y-336282D01*
X467784Y-338032D01*
X465819Y-338908D01*
X460579D01*
G01X476987Y-328699D02*
X482446Y-346199D01*
X487905Y-328699D01*
G01X499946D02*
Y-346199D01*
G01X494924Y-328699D02*
X504968D01*
G01X284269Y-301199D02*
Y-283699D01*
X289946Y-298282D01*
X295623Y-283699D01*
Y-301199D01*
G01X307446D02*
X306136Y-300907D01*
X304826Y-299741D01*
X303952Y-297699D01*
X303516Y-295366D01*
X303952Y-293032D01*
X304826Y-290991D01*
X306136Y-289824D01*
X307446Y-289533D01*
X308756Y-289824D01*
X310066Y-290991D01*
X310939Y-293032D01*
X311158Y-295366D01*
X310939Y-297699D01*
X310066Y-299741D01*
X308756Y-300907D01*
X307446Y-301199D01*
G01X328876Y-283699D02*
Y-301199D01*
G01Y-298575D02*
X328003Y-300033D01*
X326692Y-300907D01*
X325164Y-301199D01*
X323418Y-300616D01*
X322108Y-299158D01*
X321234Y-297408D01*
X321016Y-295366D01*
X321234Y-293324D01*
X322108Y-291574D01*
X323418Y-290116D01*
X325164Y-289533D01*
X326692Y-289824D01*
X327784Y-290408D01*
X328876Y-291574D01*
G01X339171Y-293324D02*
X346158D01*
X345503Y-291282D01*
X344411Y-290116D01*
X342883Y-289533D01*
X341354Y-289824D01*
X340044Y-290699D01*
X339171Y-292741D01*
X338734Y-294491D01*
Y-296241D01*
X339171Y-297991D01*
X340263Y-299741D01*
X341573Y-300907D01*
X343101Y-301199D01*
X344629Y-300616D01*
X346158Y-298866D01*
G01X359946Y-301199D02*
Y-283699D01*
G01X556346Y-346199D02*
Y-328699D01*
X553726Y-332199D01*
G01Y-346199D02*
X558966D01*
G01X569043Y-343575D02*
X570352Y-345033D01*
X571881Y-345907D01*
X573846Y-346199D01*
X575811Y-345616D01*
X577339Y-344449D01*
X578431Y-342408D01*
X578649Y-340074D01*
X578213Y-337741D01*
X577121Y-336282D01*
X575592Y-335116D01*
X574064Y-334824D01*
X572536Y-335116D01*
X570571Y-336282D01*
X571226Y-328699D01*
X577121D01*
G01X591346Y-346199D02*
Y-328699D01*
X588726Y-332199D01*
G01Y-346199D02*
X593966D01*
G01X608846Y-328699D02*
X607099Y-329282D01*
X605789Y-330741D01*
X604916Y-332490D01*
X604261Y-334824D01*
X604043Y-337449D01*
X604261Y-340074D01*
X604916Y-342408D01*
X605789Y-344158D01*
X607099Y-345616D01*
X608846Y-346199D01*
X610592Y-345616D01*
X611903Y-344158D01*
X612776Y-342408D01*
X613431Y-340074D01*
X613649Y-337449D01*
X613431Y-334824D01*
X612776Y-332490D01*
X611903Y-330741D01*
X610592Y-329282D01*
X608846Y-328699D01*
G01X621543Y-343575D02*
X622852Y-345033D01*
X624381Y-345907D01*
X626346Y-346199D01*
X628311Y-345616D01*
X629839Y-344449D01*
X630931Y-342408D01*
X631149Y-340074D01*
X630713Y-337741D01*
X629621Y-336282D01*
X628092Y-335116D01*
X626564Y-334824D01*
X625036Y-335116D01*
X623071Y-336282D01*
X623726Y-328699D01*
X629621D01*
G01X543229Y-301199D02*
Y-283699D01*
X548469D01*
X550216Y-284574D01*
X551526Y-286616D01*
X551963Y-288949D01*
X551526Y-291282D01*
X550434Y-293032D01*
X548469Y-293908D01*
X543229D01*
G01X569899Y-285158D02*
X568589Y-284282D01*
X567061Y-283699D01*
X565314D01*
X563349Y-284574D01*
X561821Y-286032D01*
X560729Y-287783D01*
X559856Y-290699D01*
X559637Y-293324D01*
X560074Y-295949D01*
X560729Y-297699D01*
X562039Y-299449D01*
X563568Y-300616D01*
X565096Y-301199D01*
X566624D01*
X568153Y-300616D01*
X569463Y-299741D01*
X570555Y-298575D01*
G01X584342Y-291866D02*
X585216Y-290991D01*
X585871Y-289533D01*
X586308Y-287490D01*
X585871Y-285741D01*
X584998Y-284574D01*
X583469Y-283699D01*
X577574D01*
Y-301199D01*
X584779D01*
X586308Y-300033D01*
X587181Y-298282D01*
X587618Y-296241D01*
X587181Y-294199D01*
X585871Y-292449D01*
X584342Y-291866D01*
X577574D01*
G01X593546Y-307032D02*
X606646D01*
G01X612574Y-301199D02*
Y-283699D01*
X622618Y-301199D01*
Y-283699D01*
G01X635096Y-301199D02*
X633349Y-300907D01*
X631821Y-299741D01*
X630511Y-297991D01*
X629637Y-295949D01*
X629201Y-293616D01*
Y-291282D01*
X629637Y-288949D01*
X630511Y-286907D01*
X631821Y-285158D01*
X633349Y-283991D01*
X635096Y-283699D01*
X636842Y-283991D01*
X638371Y-285158D01*
X639681Y-286907D01*
X640555Y-288949D01*
X640991Y-291282D01*
Y-293616D01*
X640555Y-295949D01*
X639681Y-297991D01*
X638371Y-299741D01*
X636842Y-300907D01*
X635096Y-301199D01*
G01X685937Y-283699D02*
X691396Y-301199D01*
X696855Y-283699D01*
G01X713263Y-301199D02*
X704529D01*
Y-283699D01*
X713263D01*
G01X709769Y-292157D02*
X704529D01*
G01X722029Y-301199D02*
Y-283699D01*
X727488D01*
X729234Y-284574D01*
X730326Y-285741D01*
X730763Y-288074D01*
X730326Y-290408D01*
X729016Y-291866D01*
X727488Y-292741D01*
X722029D01*
G01X727488D02*
X730763Y-301199D01*
G01X743896Y-301782D02*
X743459Y-301491D01*
Y-300907D01*
X743896Y-300616D01*
X744333Y-300907D01*
Y-301491D01*
X743896Y-301782D01*
G01X717646Y-346199D02*
Y-328699D01*
X715026Y-332199D01*
G01Y-346199D02*
X720266D01*
G01X819043D02*
Y-328699D01*
X823409D01*
X825156Y-329574D01*
X826466Y-330741D01*
X827558Y-332490D01*
X828431Y-334533D01*
X828649Y-337449D01*
X828431Y-340366D01*
X827558Y-342408D01*
X826466Y-344158D01*
X825156Y-345324D01*
X823409Y-346199D01*
X819043D01*
G01X836979D02*
Y-328699D01*
X842438D01*
X844184Y-329574D01*
X845276Y-330741D01*
X845713Y-333074D01*
X845276Y-335408D01*
X843966Y-336866D01*
X842438Y-337741D01*
X836979D01*
G01X842438D02*
X845713Y-346199D01*
G01X856226Y-328699D02*
X861466D01*
G01X858846D02*
Y-346199D01*
G01X856226D02*
X861466D01*
G01X871979Y-328699D02*
Y-346199D01*
X880713D01*
G01X889479Y-328699D02*
Y-346199D01*
X898213D01*
G01X819479Y-283699D02*
Y-301199D01*
X828213D01*
G01X845276D02*
Y-289533D01*
G01Y-291574D02*
X844403Y-290408D01*
X843092Y-289824D01*
X841564Y-289533D01*
X840036Y-290116D01*
X838726Y-291282D01*
X837852Y-293032D01*
X837416Y-295366D01*
X837852Y-297699D01*
X838726Y-299449D01*
X840036Y-300616D01*
X841564Y-301199D01*
X843092Y-300907D01*
X844403Y-300033D01*
X845276Y-298866D01*
G01X854261Y-306449D02*
X855571Y-307032D01*
X857318Y-306449D01*
X858409Y-305283D01*
X859283Y-303824D01*
X860592Y-299158D01*
X863431Y-289533D01*
G01X856444D02*
X860592Y-299158D01*
G01X873071Y-293324D02*
X880058D01*
X879403Y-291282D01*
X878311Y-290116D01*
X876783Y-289533D01*
X875254Y-289824D01*
X873944Y-290699D01*
X873071Y-292741D01*
X872634Y-294491D01*
Y-296241D01*
X873071Y-297991D01*
X874163Y-299741D01*
X875473Y-300907D01*
X877001Y-301199D01*
X878529Y-300616D01*
X880058Y-298866D01*
G01X890789Y-301199D02*
Y-289533D01*
G01Y-291866D02*
X891881Y-290699D01*
X892973Y-289824D01*
X894501Y-289533D01*
X895592Y-289824D01*
X896903Y-290699D01*
G01X959846Y-328699D02*
X962902Y-346199D01*
X966396Y-328699D01*
X969889Y-346199D01*
X972946Y-328699D01*
G01X979529Y-346199D02*
Y-328699D01*
X984769D01*
X986516Y-329574D01*
X987826Y-331616D01*
X988263Y-333949D01*
X987826Y-336282D01*
X986734Y-338032D01*
X984769Y-338908D01*
X979529D01*
G01X996811Y-346199D02*
Y-328699D01*
G01X1005981D02*
Y-346199D01*
G01Y-337449D02*
X996811D01*
G01X1016058Y-340366D02*
X1021734D01*
G01X1031593Y-346199D02*
Y-328699D01*
G01X1039889D02*
X1031593Y-339491D01*
G01X1041199Y-346199D02*
X1035304Y-334533D01*
G01X1058263Y-346199D02*
X1049529D01*
Y-328699D01*
X1058263D01*
G01X1054769Y-337157D02*
X1049529D01*
G01X1066374Y-346199D02*
Y-328699D01*
X1076418Y-346199D01*
Y-328699D01*
G01X1083874Y-346199D02*
Y-328699D01*
X1093918Y-346199D01*
Y-328699D01*
G01X961593Y-301199D02*
Y-283699D01*
X965959D01*
X967706Y-284574D01*
X969016Y-285741D01*
X970108Y-287490D01*
X970981Y-289533D01*
X971199Y-292449D01*
X970981Y-295366D01*
X970108Y-297408D01*
X969016Y-299158D01*
X967706Y-300324D01*
X965959Y-301199D01*
X961593D01*
G01X980621Y-293324D02*
X987608D01*
X986953Y-291282D01*
X985861Y-290116D01*
X984333Y-289533D01*
X982804Y-289824D01*
X981494Y-290699D01*
X980621Y-292741D01*
X980184Y-294491D01*
Y-296241D01*
X980621Y-297991D01*
X981713Y-299741D01*
X983023Y-300907D01*
X984551Y-301199D01*
X986079Y-300616D01*
X987608Y-298866D01*
G01X998121Y-299158D02*
X999213Y-300324D01*
X1000741Y-301199D01*
X1002051D01*
X1003361Y-300616D01*
X1004234Y-299741D01*
X1004671Y-298575D01*
X1004453Y-296824D01*
X1003579Y-295949D01*
X999649Y-294199D01*
X998776Y-292157D01*
X999213Y-290699D01*
X1000086Y-289824D01*
X1001396Y-289533D01*
X1002706Y-289824D01*
X1004016Y-290699D01*
G01X1018896Y-289533D02*
Y-301199D01*
G01Y-284866D02*
X1018459Y-284574D01*
Y-283991D01*
X1018896Y-283699D01*
X1019333Y-283991D01*
Y-284574D01*
X1018896Y-284866D01*
G01X1033339Y-305574D02*
X1034868Y-306741D01*
X1036614Y-307032D01*
X1038142Y-306741D01*
X1039453Y-305283D01*
X1040326Y-303241D01*
Y-289533D01*
G01Y-291866D02*
X1039453Y-290699D01*
X1038142Y-289824D01*
X1036614Y-289533D01*
X1034868Y-290116D01*
X1033776Y-291282D01*
X1032902Y-293324D01*
X1032466Y-295366D01*
X1032684Y-297116D01*
X1033558Y-299158D01*
X1034868Y-300616D01*
X1036614Y-301199D01*
X1037924Y-300907D01*
X1039453Y-299741D01*
X1040326Y-298575D01*
G01X1050184Y-301199D02*
Y-289533D01*
G01Y-292449D02*
X1051058Y-290991D01*
X1052368Y-289824D01*
X1054114Y-289533D01*
X1055642Y-289824D01*
X1056953Y-290991D01*
X1057608Y-293032D01*
Y-301199D01*
G01X1068121Y-293324D02*
X1075108D01*
X1074453Y-291282D01*
X1073361Y-290116D01*
X1071833Y-289533D01*
X1070304Y-289824D01*
X1068994Y-290699D01*
X1068121Y-292741D01*
X1067684Y-294491D01*
Y-296241D01*
X1068121Y-297991D01*
X1069213Y-299741D01*
X1070523Y-300907D01*
X1072051Y-301199D01*
X1073579Y-300616D01*
X1075108Y-298866D01*
G01X1085839Y-301199D02*
Y-289533D01*
G01Y-291866D02*
X1086931Y-290699D01*
X1088023Y-289824D01*
X1089551Y-289533D01*
X1090642Y-289824D01*
X1091953Y-290699D01*
G01X1132596Y-346199D02*
Y-328699D01*
X1129976Y-332199D01*
G01Y-346199D02*
X1135216D01*
G01X1150096D02*
Y-328699D01*
X1147476Y-332199D01*
G01Y-346199D02*
X1152716D01*
G01X1163666Y-346782D02*
X1171526Y-328699D01*
G01X1185096Y-346199D02*
Y-328699D01*
X1182476Y-332199D01*
G01Y-346199D02*
X1187716D01*
G01X1198448Y-338908D02*
X1199976Y-336866D01*
X1201286Y-335699D01*
X1203033Y-335116D01*
X1204561Y-335699D01*
X1205653Y-336866D01*
X1206526Y-338616D01*
X1206744Y-340657D01*
X1206526Y-342408D01*
X1205653Y-344158D01*
X1204342Y-345616D01*
X1202814Y-346199D01*
X1201068Y-345616D01*
X1199539Y-343866D01*
X1198666Y-341241D01*
X1198448Y-338324D01*
X1198884Y-334533D01*
X1199539Y-332490D01*
X1200631Y-330449D01*
X1202159Y-328991D01*
X1203688Y-328699D01*
X1205216Y-329282D01*
X1206308Y-330741D01*
G01X1216166Y-346782D02*
X1224026Y-328699D01*
G01X1233448Y-331616D02*
X1234758Y-329866D01*
X1236286Y-328991D01*
X1238033Y-328699D01*
X1240216Y-329282D01*
X1241744Y-330741D01*
X1242181Y-332490D01*
X1241963Y-334241D01*
X1241089Y-335699D01*
X1236723Y-338616D01*
X1234758Y-340657D01*
X1233448Y-343575D01*
X1233011Y-346199D01*
X1242181D01*
G01X1255096Y-328699D02*
X1253349Y-329282D01*
X1252039Y-330741D01*
X1251166Y-332490D01*
X1250511Y-334824D01*
X1250293Y-337449D01*
X1250511Y-340074D01*
X1251166Y-342408D01*
X1252039Y-344158D01*
X1253349Y-345616D01*
X1255096Y-346199D01*
X1256842Y-345616D01*
X1258153Y-344158D01*
X1259026Y-342408D01*
X1259681Y-340074D01*
X1259899Y-337449D01*
X1259681Y-334824D01*
X1259026Y-332490D01*
X1258153Y-330741D01*
X1256842Y-329282D01*
X1255096Y-328699D01*
G01X1272596Y-346199D02*
Y-328699D01*
X1269976Y-332199D01*
G01Y-346199D02*
X1275216D01*
G01X1285948Y-338908D02*
X1287476Y-336866D01*
X1288786Y-335699D01*
X1290533Y-335116D01*
X1292061Y-335699D01*
X1293153Y-336866D01*
X1294026Y-338616D01*
X1294244Y-340657D01*
X1294026Y-342408D01*
X1293153Y-344158D01*
X1291842Y-345616D01*
X1290314Y-346199D01*
X1288568Y-345616D01*
X1287039Y-343866D01*
X1286166Y-341241D01*
X1285948Y-338324D01*
X1286384Y-334533D01*
X1287039Y-332490D01*
X1288131Y-330449D01*
X1289659Y-328991D01*
X1291188Y-328699D01*
X1292716Y-329282D01*
X1293808Y-330741D01*
G01X1180293Y-301199D02*
Y-283699D01*
X1184659D01*
X1186406Y-284574D01*
X1187716Y-285741D01*
X1188808Y-287490D01*
X1189681Y-289533D01*
X1189899Y-292449D01*
X1189681Y-295366D01*
X1188808Y-297408D01*
X1187716Y-299158D01*
X1186406Y-300324D01*
X1184659Y-301199D01*
X1180293D01*
G01X1206526D02*
Y-289533D01*
G01Y-291574D02*
X1205653Y-290408D01*
X1204342Y-289824D01*
X1202814Y-289533D01*
X1201286Y-290116D01*
X1199976Y-291282D01*
X1199102Y-293032D01*
X1198666Y-295366D01*
X1199102Y-297699D01*
X1199976Y-299449D01*
X1201286Y-300616D01*
X1202814Y-301199D01*
X1204342Y-300907D01*
X1205653Y-300033D01*
X1206526Y-298866D01*
G01X1220096Y-283699D02*
Y-301199D01*
G01X1217039Y-289533D02*
X1223153D01*
G01X1234321Y-293324D02*
X1241308D01*
X1240653Y-291282D01*
X1239561Y-290116D01*
X1238033Y-289533D01*
X1236504Y-289824D01*
X1235194Y-290699D01*
X1234321Y-292741D01*
X1233884Y-294491D01*
Y-296241D01*
X1234321Y-297991D01*
X1235413Y-299741D01*
X1236723Y-300907D01*
X1238251Y-301199D01*
X1239779Y-300616D01*
X1241308Y-298866D01*
G01X1665111Y193656D02*
Y206156D01*
X1672241Y193656D01*
Y206156D01*
G01X1681076Y193656D02*
X1680146Y193864D01*
X1679216Y194697D01*
X1678596Y196156D01*
X1678286Y197823D01*
X1678596Y199489D01*
X1679216Y200948D01*
X1680146Y201781D01*
X1681076Y201989D01*
X1682006Y201781D01*
X1682936Y200948D01*
X1683556Y199489D01*
X1683711Y197823D01*
X1683556Y196156D01*
X1682936Y194697D01*
X1682006Y193864D01*
X1681076Y193656D01*
G01X1693476Y206156D02*
Y193656D01*
G01X1691306Y201989D02*
X1695646D01*
G01X1703551Y199281D02*
X1708511D01*
X1708046Y200739D01*
X1707271Y201573D01*
X1706186Y201989D01*
X1705101Y201781D01*
X1704171Y201156D01*
X1703551Y199698D01*
X1703241Y198447D01*
Y197198D01*
X1703551Y195948D01*
X1704326Y194697D01*
X1705256Y193864D01*
X1706341Y193656D01*
X1707426Y194073D01*
X1708511Y195322D01*
G01X1718276Y193239D02*
X1717966Y193448D01*
Y193864D01*
X1718276Y194073D01*
X1718586Y193864D01*
Y193448D01*
X1718276Y193239D01*
G01Y198864D02*
X1717966Y199073D01*
Y199489D01*
X1718276Y199698D01*
X1718586Y199489D01*
Y199073D01*
X1718276Y198864D01*
G01X1727576Y193656D02*
Y206156D01*
X1731451D01*
X1732691Y205531D01*
X1733466Y204698D01*
X1733776Y203031D01*
X1733466Y201364D01*
X1732536Y200323D01*
X1731451Y199698D01*
X1727576D01*
G01X1731451D02*
X1733776Y193656D01*
G01X1740751Y199281D02*
X1745711D01*
X1745246Y200739D01*
X1744471Y201573D01*
X1743386Y201989D01*
X1742301Y201781D01*
X1741371Y201156D01*
X1740751Y199698D01*
X1740441Y198447D01*
Y197198D01*
X1740751Y195948D01*
X1741526Y194697D01*
X1742456Y193864D01*
X1743541Y193656D01*
X1744626Y194073D01*
X1745711Y195322D01*
G01X1754546Y193656D02*
Y204281D01*
X1754856Y205322D01*
X1755476Y205948D01*
X1756406Y206156D01*
X1757336Y205739D01*
X1757801Y204698D01*
G01X1755941Y201156D02*
X1752841D01*
G01X1765551Y199281D02*
X1770511D01*
X1770046Y200739D01*
X1769271Y201573D01*
X1768186Y201989D01*
X1767101Y201781D01*
X1766171Y201156D01*
X1765551Y199698D01*
X1765241Y198447D01*
Y197198D01*
X1765551Y195948D01*
X1766326Y194697D01*
X1767256Y193864D01*
X1768341Y193656D01*
X1769426Y194073D01*
X1770511Y195322D01*
G01X1778106Y193656D02*
Y201989D01*
G01Y200323D02*
X1778881Y201156D01*
X1779656Y201781D01*
X1780741Y201989D01*
X1781516Y201781D01*
X1782446Y201156D01*
G01X1805076Y206156D02*
Y193656D01*
G01X1802906Y201989D02*
X1807246D01*
G01X1817476Y193656D02*
X1816546Y193864D01*
X1815616Y194697D01*
X1814996Y196156D01*
X1814686Y197823D01*
X1814996Y199489D01*
X1815616Y200948D01*
X1816546Y201781D01*
X1817476Y201989D01*
X1818406Y201781D01*
X1819336Y200948D01*
X1819956Y199489D01*
X1820111Y197823D01*
X1819956Y196156D01*
X1819336Y194697D01*
X1818406Y193864D01*
X1817476Y193656D01*
G01X1838866D02*
Y206156D01*
X1841966D01*
X1843206Y205531D01*
X1844136Y204698D01*
X1844911Y203448D01*
X1845531Y201989D01*
X1845686Y199906D01*
X1845531Y197823D01*
X1844911Y196364D01*
X1844136Y195114D01*
X1843206Y194281D01*
X1841966Y193656D01*
X1838866D01*
G01X1851576D02*
Y206156D01*
X1855451D01*
X1856691Y205531D01*
X1857466Y204698D01*
X1857776Y203031D01*
X1857466Y201364D01*
X1856536Y200323D01*
X1855451Y199698D01*
X1851576D01*
G01X1855451D02*
X1857776Y193656D01*
G01X1865216Y206156D02*
X1868936D01*
G01X1867076D02*
Y193656D01*
G01X1865216D02*
X1868936D01*
G01X1876376Y206156D02*
Y193656D01*
X1882576D01*
G01X1888776Y206156D02*
Y193656D01*
X1894976D01*
G01X1916676D02*
Y206156D01*
G01X1931866Y193656D02*
Y201989D01*
G01Y200531D02*
X1931246Y201364D01*
X1930316Y201781D01*
X1929231Y201989D01*
X1928146Y201573D01*
X1927216Y200739D01*
X1926596Y199489D01*
X1926286Y197823D01*
X1926596Y196156D01*
X1927216Y194906D01*
X1928146Y194073D01*
X1929231Y193656D01*
X1930316Y193864D01*
X1931246Y194489D01*
X1931866Y195322D01*
G01X1938221Y189906D02*
X1939151Y189489D01*
X1940391Y189906D01*
X1941166Y190739D01*
X1941786Y191781D01*
X1942716Y195114D01*
X1944731Y201989D01*
G01X1939771D02*
X1942716Y195114D01*
G01X1951551Y199281D02*
X1956511D01*
X1956046Y200739D01*
X1955271Y201573D01*
X1954186Y201989D01*
X1953101Y201781D01*
X1952171Y201156D01*
X1951551Y199698D01*
X1951241Y198447D01*
Y197198D01*
X1951551Y195948D01*
X1952326Y194697D01*
X1953256Y193864D01*
X1954341Y193656D01*
X1955426Y194073D01*
X1956511Y195322D01*
G01X1964106Y193656D02*
Y201989D01*
G01Y200323D02*
X1964881Y201156D01*
X1965656Y201781D01*
X1966741Y201989D01*
X1967516Y201781D01*
X1968446Y201156D01*
G01X1990146Y193656D02*
Y204281D01*
X1990456Y205322D01*
X1991076Y205948D01*
X1992006Y206156D01*
X1992936Y205739D01*
X1993401Y204698D01*
G01X1991541Y201156D02*
X1988441D01*
G01X2003476Y193656D02*
X2002546Y193864D01*
X2001616Y194697D01*
X2000996Y196156D01*
X2000686Y197823D01*
X2000996Y199489D01*
X2001616Y200948D01*
X2002546Y201781D01*
X2003476Y201989D01*
X2004406Y201781D01*
X2005336Y200948D01*
X2005956Y199489D01*
X2006111Y197823D01*
X2005956Y196156D01*
X2005336Y194697D01*
X2004406Y193864D01*
X2003476Y193656D01*
G01X2013706D02*
Y201989D01*
G01Y200323D02*
X2014481Y201156D01*
X2015256Y201781D01*
X2016341Y201989D01*
X2017116Y201781D01*
X2018046Y201156D01*
G01X2043776Y193656D02*
X2037576D01*
Y206156D01*
X2043776D01*
G01X2041296Y200114D02*
X2037576D01*
G01X2049976Y206156D02*
Y193656D01*
X2056176D01*
G01X2062376Y206156D02*
Y193656D01*
X2068576D01*
G01X2076016Y206156D02*
X2079736D01*
G01X2077876D02*
Y193656D01*
G01X2076016D02*
X2079736D01*
G01X2087176D02*
Y206156D01*
X2090896D01*
X2092136Y205531D01*
X2093066Y204073D01*
X2093376Y202406D01*
X2093066Y200739D01*
X2092291Y199489D01*
X2090896Y198864D01*
X2087176D01*
G01X2099421Y195322D02*
X2100661Y194281D01*
X2102056Y193656D01*
X2103296D01*
X2104536Y194281D01*
X2105466Y195322D01*
X2105931Y196781D01*
X2105621Y198239D01*
X2104846Y199489D01*
X2103451Y200323D01*
X2101591Y200739D01*
X2100506Y201573D01*
X2100041Y203031D01*
X2100351Y204489D01*
X2101126Y205531D01*
X2102211Y206156D01*
X2103296D01*
X2104381Y205739D01*
X2105311Y204698D01*
G01X2118176Y193656D02*
X2111976D01*
Y206156D01*
X2118176D01*
G01X2115696Y200114D02*
X2111976D01*
G01X2142666Y206156D02*
Y193656D01*
G01Y195531D02*
X2142046Y194489D01*
X2141116Y193864D01*
X2140031Y193656D01*
X2138791Y194073D01*
X2137861Y195114D01*
X2137241Y196364D01*
X2137086Y197823D01*
X2137241Y199281D01*
X2137861Y200531D01*
X2138791Y201573D01*
X2140031Y201989D01*
X2141116Y201781D01*
X2141891Y201364D01*
X2142666Y200531D01*
G01X2150106Y193656D02*
Y201989D01*
G01Y200323D02*
X2150881Y201156D01*
X2151656Y201781D01*
X2152741Y201989D01*
X2153516Y201781D01*
X2154446Y201156D01*
G01X2164676Y201989D02*
Y193656D01*
G01Y205322D02*
X2164366Y205531D01*
Y205948D01*
X2164676Y206156D01*
X2164986Y205948D01*
Y205531D01*
X2164676Y205322D01*
G01X2177076Y193656D02*
Y206156D01*
G01X2189476Y193656D02*
Y206156D01*
G01X2217066D02*
Y193656D01*
G01Y195531D02*
X2216446Y194489D01*
X2215516Y193864D01*
X2214431Y193656D01*
X2213191Y194073D01*
X2212261Y195114D01*
X2211641Y196364D01*
X2211486Y197823D01*
X2211641Y199281D01*
X2212261Y200531D01*
X2213191Y201573D01*
X2214431Y201989D01*
X2215516Y201781D01*
X2216291Y201364D01*
X2217066Y200531D01*
G01X2226676Y201989D02*
Y193656D01*
G01Y205322D02*
X2226366Y205531D01*
Y205948D01*
X2226676Y206156D01*
X2226986Y205948D01*
Y205531D01*
X2226676Y205322D01*
G01X2236906Y193656D02*
Y201989D01*
G01Y200323D02*
X2237681Y201156D01*
X2238456Y201781D01*
X2239541Y201989D01*
X2240316Y201781D01*
X2241246Y201156D01*
G01X2249151Y199281D02*
X2254111D01*
X2253646Y200739D01*
X2252871Y201573D01*
X2251786Y201989D01*
X2250701Y201781D01*
X2249771Y201156D01*
X2249151Y199698D01*
X2248841Y198447D01*
Y197198D01*
X2249151Y195948D01*
X2249926Y194697D01*
X2250856Y193864D01*
X2251941Y193656D01*
X2253026Y194073D01*
X2254111Y195322D01*
G01X2266356Y200948D02*
X2265271Y201781D01*
X2264341Y201989D01*
X2263101Y201573D01*
X2262171Y200739D01*
X2261551Y199281D01*
X2261396Y197823D01*
X2261551Y196364D01*
X2262171Y195114D01*
X2263101Y194073D01*
X2264341Y193656D01*
X2265426Y194073D01*
X2266356Y194906D01*
G01X2276276Y206156D02*
Y193656D01*
G01X2274106Y201989D02*
X2278446D01*
G01X2288676D02*
Y193656D01*
G01Y205322D02*
X2288366Y205531D01*
Y205948D01*
X2288676Y206156D01*
X2288986Y205948D01*
Y205531D01*
X2288676Y205322D01*
G01X2301076Y193656D02*
X2300146Y193864D01*
X2299216Y194697D01*
X2298596Y196156D01*
X2298286Y197823D01*
X2298596Y199489D01*
X2299216Y200948D01*
X2300146Y201781D01*
X2301076Y201989D01*
X2302006Y201781D01*
X2302936Y200948D01*
X2303556Y199489D01*
X2303711Y197823D01*
X2303556Y196156D01*
X2302936Y194697D01*
X2302006Y193864D01*
X2301076Y193656D01*
G01X2310841D02*
Y201989D01*
G01Y199906D02*
X2311461Y200948D01*
X2312391Y201781D01*
X2313631Y201989D01*
X2314716Y201781D01*
X2315646Y200948D01*
X2316111Y199489D01*
Y193656D01*
G01X1664026Y223656D02*
Y979256D01*
X2147626D01*
Y223656D01*
X1664026D01*
G01Y251756D02*
X2147626D01*
G01X1664026Y307956D02*
X2147626D01*
G01X1664026Y279856D02*
X2147626D01*
G01X1664026Y336056D02*
X2147626D01*
G01X1664026Y364156D02*
X2147626D01*
G01X1664026Y392256D02*
X2147626D01*
G01X1664026Y420356D02*
X2147626D01*
G01X1664026Y476556D02*
X2147626D01*
G01X1664026Y448456D02*
X2147626D01*
G01X1664026Y504656D02*
X2147626D01*
G01X1664026Y532756D02*
X2147626D01*
G01X1664026Y560856D02*
X2147626D01*
G01X1664026Y588956D02*
X2147626D01*
G01X1664026Y645156D02*
X2147626D01*
G01X1664026Y617056D02*
X2147626D01*
G01X1664026Y673256D02*
X2147626D01*
G01X1664026Y701356D02*
X2147626D01*
G01X1664026Y729456D02*
X2147626D01*
G01X1664026Y757556D02*
X2147626D01*
G01X1664026Y813756D02*
X2147626D01*
G01X1664026Y785656D02*
X2147626D01*
G01X1664026Y841856D02*
X2147626D01*
G01X1664026Y869956D02*
X2147626D01*
G01X1675031Y907406D02*
Y919906D01*
X1680921D01*
G01X1678751Y913864D02*
X1675031D01*
G01X1688516Y919906D02*
X1692236D01*
G01X1690376D02*
Y907406D01*
G01X1688516D02*
X1692236D01*
G01X1703706Y913656D02*
X1706806D01*
Y909906D01*
X1705876Y908656D01*
X1704791Y907823D01*
X1703241Y907406D01*
X1701691Y907823D01*
X1700606Y908656D01*
X1699676Y909906D01*
X1699056Y911364D01*
X1698746Y913031D01*
Y914489D01*
X1699056Y915739D01*
X1699676Y917198D01*
X1700606Y918448D01*
X1701536Y919281D01*
X1702776Y919906D01*
X1703861D01*
X1705101Y919489D01*
X1706031Y918656D01*
G01X1711766Y919906D02*
Y910948D01*
X1712386Y909072D01*
X1713626Y907823D01*
X1715176Y907406D01*
X1716726Y907823D01*
X1717966Y909072D01*
X1718586Y910948D01*
Y919906D01*
G01X1724476Y907406D02*
Y919906D01*
X1728351D01*
X1729591Y919281D01*
X1730366Y918448D01*
X1730676Y916781D01*
X1730366Y915114D01*
X1729436Y914073D01*
X1728351Y913448D01*
X1724476D01*
G01X1728351D02*
X1730676Y907406D01*
G01X1743076D02*
X1736876D01*
Y919906D01*
X1743076D01*
G01X1740596Y913864D02*
X1736876D01*
G01X1664026Y898056D02*
X2147626D01*
G01X1664026Y926156D02*
X2147626D01*
G01X1664026Y954256D02*
X2147626D01*
G01X1747416Y960506D02*
Y973006D01*
X1750516D01*
X1751756Y972381D01*
X1752686Y971548D01*
X1753461Y970298D01*
X1754081Y968839D01*
X1754236Y966756D01*
X1754081Y964673D01*
X1753461Y963214D01*
X1752686Y961964D01*
X1751756Y961131D01*
X1750516Y960506D01*
X1747416D01*
G01X1760126D02*
Y973006D01*
X1764001D01*
X1765241Y972381D01*
X1766016Y971548D01*
X1766326Y969881D01*
X1766016Y968214D01*
X1765086Y967173D01*
X1764001Y966548D01*
X1760126D01*
G01X1764001D02*
X1766326Y960506D01*
G01X1773766Y973006D02*
X1777486D01*
G01X1775626D02*
Y960506D01*
G01X1773766D02*
X1777486D01*
G01X1784926Y973006D02*
Y960506D01*
X1791126D01*
G01X1797326Y973006D02*
Y960506D01*
X1803526D01*
G01X1828636Y971964D02*
X1827706Y972589D01*
X1826621Y973006D01*
X1825381D01*
X1823986Y972381D01*
X1822901Y971339D01*
X1822126Y970089D01*
X1821506Y968006D01*
X1821351Y966131D01*
X1821661Y964256D01*
X1822126Y963006D01*
X1823056Y961756D01*
X1824141Y960923D01*
X1825226Y960506D01*
X1826311D01*
X1827396Y960923D01*
X1828326Y961547D01*
X1829101Y962381D01*
G01X1834371Y960506D02*
Y973006D01*
G01X1840881D02*
Y960506D01*
G01Y966756D02*
X1834371D01*
G01X1846151Y960506D02*
X1850026Y973006D01*
X1853901Y960506D01*
G01X1852506Y964881D02*
X1847546D01*
G01X1859326Y960506D02*
Y973006D01*
X1863201D01*
X1864441Y972381D01*
X1865216Y971548D01*
X1865526Y969881D01*
X1865216Y968214D01*
X1864286Y967173D01*
X1863201Y966548D01*
X1859326D01*
G01X1863201D02*
X1865526Y960506D01*
G01X1874826Y973006D02*
Y960506D01*
G01X1871261Y973006D02*
X1878391D01*
G01X1887226Y960089D02*
X1886916Y960298D01*
Y960714D01*
X1887226Y960923D01*
X1887536Y960714D01*
Y960298D01*
X1887226Y960089D01*
G01Y965714D02*
X1886916Y965923D01*
Y966339D01*
X1887226Y966548D01*
X1887536Y966339D01*
Y965923D01*
X1887226Y965714D01*
G01X1912026Y973006D02*
Y960506D01*
G01X1908461Y973006D02*
X1915591D01*
G01X1924426Y960506D02*
X1923186Y960714D01*
X1922101Y961547D01*
X1921171Y962798D01*
X1920551Y964256D01*
X1920241Y965923D01*
Y967589D01*
X1920551Y969256D01*
X1921171Y970714D01*
X1922101Y971964D01*
X1923186Y972798D01*
X1924426Y973006D01*
X1925666Y972798D01*
X1926751Y971964D01*
X1927681Y970714D01*
X1928301Y969256D01*
X1928611Y967589D01*
Y965923D01*
X1928301Y964256D01*
X1927681Y962798D01*
X1926751Y961547D01*
X1925666Y960714D01*
X1924426Y960506D01*
G01X1933726D02*
Y973006D01*
X1937446D01*
X1938686Y972381D01*
X1939616Y970923D01*
X1939926Y969256D01*
X1939616Y967589D01*
X1938841Y966339D01*
X1937446Y965714D01*
X1933726D01*
G01X1961626Y973006D02*
Y960506D01*
G01X1959456Y968839D02*
X1963796D01*
G01X1974026Y960506D02*
X1973096Y960714D01*
X1972166Y961547D01*
X1971546Y963006D01*
X1971236Y964673D01*
X1971546Y966339D01*
X1972166Y967798D01*
X1973096Y968631D01*
X1974026Y968839D01*
X1974956Y968631D01*
X1975886Y967798D01*
X1976506Y966339D01*
X1976661Y964673D01*
X1976506Y963006D01*
X1975886Y961547D01*
X1974956Y960714D01*
X1974026Y960506D01*
G01X2000066Y967173D02*
X2000686Y967798D01*
X2001151Y968839D01*
X2001461Y970298D01*
X2001151Y971548D01*
X2000531Y972381D01*
X1999446Y973006D01*
X1995261D01*
Y960506D01*
X2000376D01*
X2001461Y961339D01*
X2002081Y962589D01*
X2002391Y964048D01*
X2002081Y965506D01*
X2001151Y966756D01*
X2000066Y967173D01*
X1995261D01*
G01X2011226Y960506D02*
X2009986Y960714D01*
X2008901Y961547D01*
X2007971Y962798D01*
X2007351Y964256D01*
X2007041Y965923D01*
Y967589D01*
X2007351Y969256D01*
X2007971Y970714D01*
X2008901Y971964D01*
X2009986Y972798D01*
X2011226Y973006D01*
X2012466Y972798D01*
X2013551Y971964D01*
X2014481Y970714D01*
X2015101Y969256D01*
X2015411Y967589D01*
Y965923D01*
X2015101Y964256D01*
X2014481Y962798D01*
X2013551Y961547D01*
X2012466Y960714D01*
X2011226Y960506D01*
G01X2023626Y973006D02*
Y960506D01*
G01X2020061Y973006D02*
X2027191D01*
G01X2036026D02*
Y960506D01*
G01X2032461Y973006D02*
X2039591D01*
G01X2048426Y960506D02*
X2047186Y960714D01*
X2046101Y961547D01*
X2045171Y962798D01*
X2044551Y964256D01*
X2044241Y965923D01*
Y967589D01*
X2044551Y969256D01*
X2045171Y970714D01*
X2046101Y971964D01*
X2047186Y972798D01*
X2048426Y973006D01*
X2049666Y972798D01*
X2050751Y971964D01*
X2051681Y970714D01*
X2052301Y969256D01*
X2052611Y967589D01*
Y965923D01*
X2052301Y964256D01*
X2051681Y962798D01*
X2050751Y961547D01*
X2049666Y960714D01*
X2048426Y960506D01*
G01X2056796D02*
Y973006D01*
X2060826Y962589D01*
X2064856Y973006D01*
Y960506D01*
G01X1753926Y926156D02*
Y223656D01*
G01X1777951Y935506D02*
X1781826Y948006D01*
X1785701Y935506D01*
G01X1784306Y939881D02*
X1779346D01*
G01X1791126Y948006D02*
Y935506D01*
X1797326D01*
G01X1803526Y948006D02*
Y935506D01*
X1809726D01*
G01X1828016Y948006D02*
Y939048D01*
X1828636Y937172D01*
X1829876Y935923D01*
X1831426Y935506D01*
X1832976Y935923D01*
X1834216Y937172D01*
X1834836Y939048D01*
Y948006D01*
G01X1840261Y935506D02*
Y948006D01*
X1847391Y935506D01*
Y948006D01*
G01X1854366D02*
X1858086D01*
G01X1856226D02*
Y935506D01*
G01X1854366D02*
X1858086D01*
G01X1868626Y948006D02*
Y935506D01*
G01X1865061Y948006D02*
X1872191D01*
G01X1877771Y937172D02*
X1879011Y936131D01*
X1880406Y935506D01*
X1881646D01*
X1882886Y936131D01*
X1883816Y937172D01*
X1884281Y938631D01*
X1883971Y940089D01*
X1883196Y941339D01*
X1881801Y942173D01*
X1879941Y942589D01*
X1878856Y943423D01*
X1878391Y944881D01*
X1878701Y946339D01*
X1879476Y947381D01*
X1880561Y948006D01*
X1881646D01*
X1882731Y947589D01*
X1883661Y946548D01*
G01X1901951Y935506D02*
X1905826Y948006D01*
X1909701Y935506D01*
G01X1908306Y939881D02*
X1903346D01*
G01X1915126Y935506D02*
Y948006D01*
X1919001D01*
X1920241Y947381D01*
X1921016Y946548D01*
X1921326Y944881D01*
X1921016Y943214D01*
X1920086Y942173D01*
X1919001Y941548D01*
X1915126D01*
G01X1919001D02*
X1921326Y935506D01*
G01X1933726D02*
X1927526D01*
Y948006D01*
X1933726D01*
G01X1931246Y941964D02*
X1927526D01*
G01X1953566Y948006D02*
X1957286D01*
G01X1955426D02*
Y935506D01*
G01X1953566D02*
X1957286D01*
G01X1964261D02*
Y948006D01*
X1971391Y935506D01*
Y948006D01*
G01X1988596Y935506D02*
Y948006D01*
X1992626Y937589D01*
X1996656Y948006D01*
Y935506D01*
G01X2003166Y948006D02*
X2006886D01*
G01X2005026D02*
Y935506D01*
G01X2003166D02*
X2006886D01*
G01X2014326Y948006D02*
Y935506D01*
X2020526D01*
G01X2026571Y937172D02*
X2027811Y936131D01*
X2029206Y935506D01*
X2030446D01*
X2031686Y936131D01*
X2032616Y937172D01*
X2033081Y938631D01*
X2032771Y940089D01*
X2031996Y941339D01*
X2030601Y942173D01*
X2028741Y942589D01*
X2027656Y943423D01*
X2027191Y944881D01*
X2027501Y946339D01*
X2028276Y947381D01*
X2029361Y948006D01*
X2030446D01*
X2031531Y947589D01*
X2032461Y946548D01*
G01X1823676Y231456D02*
Y243956D01*
X1821816Y241456D01*
G01Y231456D02*
X1825536D01*
G01X1833131Y241873D02*
X1834061Y243122D01*
X1835146Y243748D01*
X1836386Y243956D01*
X1837936Y243539D01*
X1839021Y242498D01*
X1839331Y241248D01*
X1839176Y239997D01*
X1838556Y238956D01*
X1835456Y236873D01*
X1834061Y235414D01*
X1833131Y233331D01*
X1832821Y231456D01*
X1839331D01*
G01X1848476D02*
X1849561Y231664D01*
X1850801Y232289D01*
X1851576Y233331D01*
X1851886Y234789D01*
X1851576Y236247D01*
X1850646Y237498D01*
X1849251Y238123D01*
X1847701D01*
X1846771Y238539D01*
X1845996Y239581D01*
X1845686Y241039D01*
X1846151Y242498D01*
X1847236Y243539D01*
X1848476Y243956D01*
X1849716Y243539D01*
X1850801Y242498D01*
X1851266Y241039D01*
X1850956Y239581D01*
X1850181Y238539D01*
X1849251Y238123D01*
X1847701D01*
X1846306Y237498D01*
X1845376Y236247D01*
X1845066Y234789D01*
X1845376Y233331D01*
X1846151Y232289D01*
X1847391Y231664D01*
X1848476Y231456D01*
G01X1860876Y231039D02*
X1860566Y231248D01*
Y231664D01*
X1860876Y231873D01*
X1861186Y231664D01*
Y231248D01*
X1860876Y231039D01*
G01X1873276Y243956D02*
X1872036Y243539D01*
X1871106Y242498D01*
X1870486Y241248D01*
X1870021Y239581D01*
X1869866Y237706D01*
X1870021Y235831D01*
X1870486Y234164D01*
X1871106Y232914D01*
X1872036Y231873D01*
X1873276Y231456D01*
X1874516Y231873D01*
X1875446Y232914D01*
X1876066Y234164D01*
X1876531Y235831D01*
X1876686Y237706D01*
X1876531Y239581D01*
X1876066Y241248D01*
X1875446Y242498D01*
X1874516Y243539D01*
X1873276Y243956D01*
G01X1829876Y259556D02*
X1830961Y259764D01*
X1832201Y260389D01*
X1832976Y261431D01*
X1833286Y262889D01*
X1832976Y264347D01*
X1832046Y265598D01*
X1830651Y266223D01*
X1829101D01*
X1828171Y266639D01*
X1827396Y267681D01*
X1827086Y269139D01*
X1827551Y270598D01*
X1828636Y271639D01*
X1829876Y272056D01*
X1831116Y271639D01*
X1832201Y270598D01*
X1832666Y269139D01*
X1832356Y267681D01*
X1831581Y266639D01*
X1830651Y266223D01*
X1829101D01*
X1827706Y265598D01*
X1826776Y264347D01*
X1826466Y262889D01*
X1826776Y261431D01*
X1827551Y260389D01*
X1828791Y259764D01*
X1829876Y259556D01*
G01X1839331Y264764D02*
X1840416Y266223D01*
X1841346Y267056D01*
X1842586Y267473D01*
X1843671Y267056D01*
X1844446Y266223D01*
X1845066Y264973D01*
X1845221Y263514D01*
X1845066Y262264D01*
X1844446Y261014D01*
X1843516Y259973D01*
X1842431Y259556D01*
X1841191Y259973D01*
X1840106Y261222D01*
X1839486Y263098D01*
X1839331Y265181D01*
X1839641Y267889D01*
X1840106Y269348D01*
X1840881Y270806D01*
X1841966Y271848D01*
X1843051Y272056D01*
X1844136Y271639D01*
X1844911Y270598D01*
G01X1854676Y259139D02*
X1854366Y259348D01*
Y259764D01*
X1854676Y259973D01*
X1854986Y259764D01*
Y259348D01*
X1854676Y259139D01*
G01X1867076Y272056D02*
X1865836Y271639D01*
X1864906Y270598D01*
X1864286Y269348D01*
X1863821Y267681D01*
X1863666Y265806D01*
X1863821Y263931D01*
X1864286Y262264D01*
X1864906Y261014D01*
X1865836Y259973D01*
X1867076Y259556D01*
X1868316Y259973D01*
X1869246Y261014D01*
X1869866Y262264D01*
X1870331Y263931D01*
X1870486Y265806D01*
X1870331Y267681D01*
X1869866Y269348D01*
X1869246Y270598D01*
X1868316Y271639D01*
X1867076Y272056D01*
G01X1831736Y287656D02*
Y300156D01*
X1826001Y291198D01*
X1833751D01*
G01X1842276Y300156D02*
X1841036Y299739D01*
X1840106Y298698D01*
X1839486Y297448D01*
X1839021Y295781D01*
X1838866Y293906D01*
X1839021Y292031D01*
X1839486Y290364D01*
X1840106Y289114D01*
X1841036Y288073D01*
X1842276Y287656D01*
X1843516Y288073D01*
X1844446Y289114D01*
X1845066Y290364D01*
X1845531Y292031D01*
X1845686Y293906D01*
X1845531Y295781D01*
X1845066Y297448D01*
X1844446Y298698D01*
X1843516Y299739D01*
X1842276Y300156D01*
G01X1854676Y287239D02*
X1854366Y287448D01*
Y287864D01*
X1854676Y288073D01*
X1854986Y287864D01*
Y287448D01*
X1854676Y287239D01*
G01X1867076Y300156D02*
X1865836Y299739D01*
X1864906Y298698D01*
X1864286Y297448D01*
X1863821Y295781D01*
X1863666Y293906D01*
X1863821Y292031D01*
X1864286Y290364D01*
X1864906Y289114D01*
X1865836Y288073D01*
X1867076Y287656D01*
X1868316Y288073D01*
X1869246Y289114D01*
X1869866Y290364D01*
X1870331Y292031D01*
X1870486Y293906D01*
X1870331Y295781D01*
X1869866Y297448D01*
X1869246Y298698D01*
X1868316Y299739D01*
X1867076Y300156D01*
G01X1826466Y346356D02*
X1827396Y344897D01*
X1828636Y344064D01*
X1830031Y343856D01*
X1831271Y344064D01*
X1832511Y345106D01*
X1833286Y346356D01*
X1833441Y347606D01*
X1833131Y349064D01*
X1832046Y350106D01*
X1830961Y350523D01*
X1829566D01*
G01X1830961D02*
X1831891Y351148D01*
X1832666Y352189D01*
X1832976Y353439D01*
X1832666Y354689D01*
X1831891Y355731D01*
X1830496Y356356D01*
X1829101Y356148D01*
X1827706Y355314D01*
G01X1839331Y354273D02*
X1840261Y355522D01*
X1841346Y356148D01*
X1842586Y356356D01*
X1844136Y355939D01*
X1845221Y354898D01*
X1845531Y353648D01*
X1845376Y352397D01*
X1844756Y351356D01*
X1841656Y349273D01*
X1840261Y347814D01*
X1839331Y345731D01*
X1839021Y343856D01*
X1845531D01*
G01X1854676Y343439D02*
X1854366Y343648D01*
Y344064D01*
X1854676Y344273D01*
X1854986Y344064D01*
Y343648D01*
X1854676Y343439D01*
G01X1867076Y356356D02*
X1865836Y355939D01*
X1864906Y354898D01*
X1864286Y353648D01*
X1863821Y351981D01*
X1863666Y350106D01*
X1863821Y348231D01*
X1864286Y346564D01*
X1864906Y345314D01*
X1865836Y344273D01*
X1867076Y343856D01*
X1868316Y344273D01*
X1869246Y345314D01*
X1869866Y346564D01*
X1870331Y348231D01*
X1870486Y350106D01*
X1870331Y351981D01*
X1869866Y353648D01*
X1869246Y354898D01*
X1868316Y355939D01*
X1867076Y356356D01*
G01X1826466Y318256D02*
X1827396Y316797D01*
X1828636Y315964D01*
X1830031Y315756D01*
X1831271Y315964D01*
X1832511Y317006D01*
X1833286Y318256D01*
X1833441Y319506D01*
X1833131Y320964D01*
X1832046Y322006D01*
X1830961Y322423D01*
X1829566D01*
G01X1830961D02*
X1831891Y323048D01*
X1832666Y324089D01*
X1832976Y325339D01*
X1832666Y326589D01*
X1831891Y327631D01*
X1830496Y328256D01*
X1829101Y328048D01*
X1827706Y327214D01*
G01X1842276Y315756D02*
X1843361Y315964D01*
X1844601Y316589D01*
X1845376Y317631D01*
X1845686Y319089D01*
X1845376Y320547D01*
X1844446Y321798D01*
X1843051Y322423D01*
X1841501D01*
X1840571Y322839D01*
X1839796Y323881D01*
X1839486Y325339D01*
X1839951Y326798D01*
X1841036Y327839D01*
X1842276Y328256D01*
X1843516Y327839D01*
X1844601Y326798D01*
X1845066Y325339D01*
X1844756Y323881D01*
X1843981Y322839D01*
X1843051Y322423D01*
X1841501D01*
X1840106Y321798D01*
X1839176Y320547D01*
X1838866Y319089D01*
X1839176Y317631D01*
X1839951Y316589D01*
X1841191Y315964D01*
X1842276Y315756D01*
G01X1854676Y315339D02*
X1854366Y315548D01*
Y315964D01*
X1854676Y316173D01*
X1854986Y315964D01*
Y315548D01*
X1854676Y315339D01*
G01X1867076Y328256D02*
X1865836Y327839D01*
X1864906Y326798D01*
X1864286Y325548D01*
X1863821Y323881D01*
X1863666Y322006D01*
X1863821Y320131D01*
X1864286Y318464D01*
X1864906Y317214D01*
X1865836Y316173D01*
X1867076Y315756D01*
X1868316Y316173D01*
X1869246Y317214D01*
X1869866Y318464D01*
X1870331Y320131D01*
X1870486Y322006D01*
X1870331Y323881D01*
X1869866Y325548D01*
X1869246Y326798D01*
X1868316Y327839D01*
X1867076Y328256D01*
G01X1823676Y371956D02*
Y384456D01*
X1821816Y381956D01*
G01Y371956D02*
X1825536D01*
G01X1833131Y377164D02*
X1834216Y378623D01*
X1835146Y379456D01*
X1836386Y379873D01*
X1837471Y379456D01*
X1838246Y378623D01*
X1838866Y377373D01*
X1839021Y375914D01*
X1838866Y374664D01*
X1838246Y373414D01*
X1837316Y372373D01*
X1836231Y371956D01*
X1834991Y372373D01*
X1833906Y373622D01*
X1833286Y375498D01*
X1833131Y377581D01*
X1833441Y380289D01*
X1833906Y381748D01*
X1834681Y383206D01*
X1835766Y384248D01*
X1836851Y384456D01*
X1837936Y384039D01*
X1838711Y382998D01*
G01X1848476Y371956D02*
X1849561Y372164D01*
X1850801Y372789D01*
X1851576Y373831D01*
X1851886Y375289D01*
X1851576Y376747D01*
X1850646Y377998D01*
X1849251Y378623D01*
X1847701D01*
X1846771Y379039D01*
X1845996Y380081D01*
X1845686Y381539D01*
X1846151Y382998D01*
X1847236Y384039D01*
X1848476Y384456D01*
X1849716Y384039D01*
X1850801Y382998D01*
X1851266Y381539D01*
X1850956Y380081D01*
X1850181Y379039D01*
X1849251Y378623D01*
X1847701D01*
X1846306Y377998D01*
X1845376Y376747D01*
X1845066Y375289D01*
X1845376Y373831D01*
X1846151Y372789D01*
X1847391Y372164D01*
X1848476Y371956D01*
G01X1860876Y371539D02*
X1860566Y371748D01*
Y372164D01*
X1860876Y372373D01*
X1861186Y372164D01*
Y371748D01*
X1860876Y371539D01*
G01X1873276Y384456D02*
X1872036Y384039D01*
X1871106Y382998D01*
X1870486Y381748D01*
X1870021Y380081D01*
X1869866Y378206D01*
X1870021Y376331D01*
X1870486Y374664D01*
X1871106Y373414D01*
X1872036Y372373D01*
X1873276Y371956D01*
X1874516Y372373D01*
X1875446Y373414D01*
X1876066Y374664D01*
X1876531Y376331D01*
X1876686Y378206D01*
X1876531Y380081D01*
X1876066Y381748D01*
X1875446Y382998D01*
X1874516Y384039D01*
X1873276Y384456D01*
G01X1823676Y400056D02*
Y412556D01*
X1821816Y410056D01*
G01Y400056D02*
X1825536D01*
G01X1832666Y401931D02*
X1833596Y400889D01*
X1834681Y400264D01*
X1836076Y400056D01*
X1837471Y400473D01*
X1838556Y401306D01*
X1839331Y402764D01*
X1839486Y404431D01*
X1839176Y406098D01*
X1838401Y407139D01*
X1837316Y407973D01*
X1836231Y408181D01*
X1835146Y407973D01*
X1833751Y407139D01*
X1834216Y412556D01*
X1838401D01*
G01X1848476D02*
X1847236Y412139D01*
X1846306Y411098D01*
X1845686Y409848D01*
X1845221Y408181D01*
X1845066Y406306D01*
X1845221Y404431D01*
X1845686Y402764D01*
X1846306Y401514D01*
X1847236Y400473D01*
X1848476Y400056D01*
X1849716Y400473D01*
X1850646Y401514D01*
X1851266Y402764D01*
X1851731Y404431D01*
X1851886Y406306D01*
X1851731Y408181D01*
X1851266Y409848D01*
X1850646Y411098D01*
X1849716Y412139D01*
X1848476Y412556D01*
G01X1860876Y399639D02*
X1860566Y399848D01*
Y400264D01*
X1860876Y400473D01*
X1861186Y400264D01*
Y399848D01*
X1860876Y399639D01*
G01X1873276Y412556D02*
X1872036Y412139D01*
X1871106Y411098D01*
X1870486Y409848D01*
X1870021Y408181D01*
X1869866Y406306D01*
X1870021Y404431D01*
X1870486Y402764D01*
X1871106Y401514D01*
X1872036Y400473D01*
X1873276Y400056D01*
X1874516Y400473D01*
X1875446Y401514D01*
X1876066Y402764D01*
X1876531Y404431D01*
X1876686Y406306D01*
X1876531Y408181D01*
X1876066Y409848D01*
X1875446Y411098D01*
X1874516Y412139D01*
X1873276Y412556D01*
G01X1823676Y428156D02*
Y440656D01*
X1821816Y438156D01*
G01Y428156D02*
X1825536D01*
G01X1833131Y438573D02*
X1834061Y439822D01*
X1835146Y440448D01*
X1836386Y440656D01*
X1837936Y440239D01*
X1839021Y439198D01*
X1839331Y437948D01*
X1839176Y436697D01*
X1838556Y435656D01*
X1835456Y433573D01*
X1834061Y432114D01*
X1833131Y430031D01*
X1832821Y428156D01*
X1839331D01*
G01X1845531Y433364D02*
X1846616Y434823D01*
X1847546Y435656D01*
X1848786Y436073D01*
X1849871Y435656D01*
X1850646Y434823D01*
X1851266Y433573D01*
X1851421Y432114D01*
X1851266Y430864D01*
X1850646Y429614D01*
X1849716Y428573D01*
X1848631Y428156D01*
X1847391Y428573D01*
X1846306Y429822D01*
X1845686Y431698D01*
X1845531Y433781D01*
X1845841Y436489D01*
X1846306Y437948D01*
X1847081Y439406D01*
X1848166Y440448D01*
X1849251Y440656D01*
X1850336Y440239D01*
X1851111Y439198D01*
G01X1860876Y427739D02*
X1860566Y427948D01*
Y428364D01*
X1860876Y428573D01*
X1861186Y428364D01*
Y427948D01*
X1860876Y427739D01*
G01X1873276Y440656D02*
X1872036Y440239D01*
X1871106Y439198D01*
X1870486Y437948D01*
X1870021Y436281D01*
X1869866Y434406D01*
X1870021Y432531D01*
X1870486Y430864D01*
X1871106Y429614D01*
X1872036Y428573D01*
X1873276Y428156D01*
X1874516Y428573D01*
X1875446Y429614D01*
X1876066Y430864D01*
X1876531Y432531D01*
X1876686Y434406D01*
X1876531Y436281D01*
X1876066Y437948D01*
X1875446Y439198D01*
X1874516Y440239D01*
X1873276Y440656D01*
G01X1827241Y457714D02*
X1828326Y456673D01*
X1829566Y456256D01*
X1830806Y456673D01*
X1831891Y457922D01*
X1832666Y459798D01*
X1832976Y461673D01*
Y463964D01*
X1832666Y465839D01*
X1831891Y467506D01*
X1830961Y468339D01*
X1829876Y468756D01*
X1828636Y468339D01*
X1827706Y467506D01*
X1827086Y466256D01*
X1826776Y464589D01*
X1827086Y463131D01*
X1827861Y461673D01*
X1828791Y460839D01*
X1829876Y460631D01*
X1831116Y461047D01*
X1832046Y462089D01*
X1832976Y463964D01*
G01X1842276Y456256D02*
Y468756D01*
X1840416Y466256D01*
G01Y456256D02*
X1844136D01*
G01X1854676Y455839D02*
X1854366Y456048D01*
Y456464D01*
X1854676Y456673D01*
X1854986Y456464D01*
Y456048D01*
X1854676Y455839D01*
G01X1867076Y468756D02*
X1865836Y468339D01*
X1864906Y467298D01*
X1864286Y466048D01*
X1863821Y464381D01*
X1863666Y462506D01*
X1863821Y460631D01*
X1864286Y458964D01*
X1864906Y457714D01*
X1865836Y456673D01*
X1867076Y456256D01*
X1868316Y456673D01*
X1869246Y457714D01*
X1869866Y458964D01*
X1870331Y460631D01*
X1870486Y462506D01*
X1870331Y464381D01*
X1869866Y466048D01*
X1869246Y467298D01*
X1868316Y468339D01*
X1867076Y468756D01*
G01X1826931Y517664D02*
X1828016Y519123D01*
X1828946Y519956D01*
X1830186Y520373D01*
X1831271Y519956D01*
X1832046Y519123D01*
X1832666Y517873D01*
X1832821Y516414D01*
X1832666Y515164D01*
X1832046Y513914D01*
X1831116Y512873D01*
X1830031Y512456D01*
X1828791Y512873D01*
X1827706Y514122D01*
X1827086Y515998D01*
X1826931Y518081D01*
X1827241Y520789D01*
X1827706Y522248D01*
X1828481Y523706D01*
X1829566Y524748D01*
X1830651Y524956D01*
X1831736Y524539D01*
X1832511Y523498D01*
G01X1839331Y522873D02*
X1840261Y524122D01*
X1841346Y524748D01*
X1842586Y524956D01*
X1844136Y524539D01*
X1845221Y523498D01*
X1845531Y522248D01*
X1845376Y520997D01*
X1844756Y519956D01*
X1841656Y517873D01*
X1840261Y516414D01*
X1839331Y514331D01*
X1839021Y512456D01*
X1845531D01*
G01X1854676Y512039D02*
X1854366Y512248D01*
Y512664D01*
X1854676Y512873D01*
X1854986Y512664D01*
Y512248D01*
X1854676Y512039D01*
G01X1867076Y524956D02*
X1865836Y524539D01*
X1864906Y523498D01*
X1864286Y522248D01*
X1863821Y520581D01*
X1863666Y518706D01*
X1863821Y516831D01*
X1864286Y515164D01*
X1864906Y513914D01*
X1865836Y512873D01*
X1867076Y512456D01*
X1868316Y512873D01*
X1869246Y513914D01*
X1869866Y515164D01*
X1870331Y516831D01*
X1870486Y518706D01*
X1870331Y520581D01*
X1869866Y522248D01*
X1869246Y523498D01*
X1868316Y524539D01*
X1867076Y524956D01*
G01X1829876Y484356D02*
X1830961Y484564D01*
X1832201Y485189D01*
X1832976Y486231D01*
X1833286Y487689D01*
X1832976Y489147D01*
X1832046Y490398D01*
X1830651Y491023D01*
X1829101D01*
X1828171Y491439D01*
X1827396Y492481D01*
X1827086Y493939D01*
X1827551Y495398D01*
X1828636Y496439D01*
X1829876Y496856D01*
X1831116Y496439D01*
X1832201Y495398D01*
X1832666Y493939D01*
X1832356Y492481D01*
X1831581Y491439D01*
X1830651Y491023D01*
X1829101D01*
X1827706Y490398D01*
X1826776Y489147D01*
X1826466Y487689D01*
X1826776Y486231D01*
X1827551Y485189D01*
X1828791Y484564D01*
X1829876Y484356D01*
G01X1841966D02*
X1842276Y487064D01*
X1842741Y489356D01*
X1843361Y491439D01*
X1844136Y493731D01*
X1845376Y496856D01*
X1839176D01*
G01X1854676Y483939D02*
X1854366Y484148D01*
Y484564D01*
X1854676Y484773D01*
X1854986Y484564D01*
Y484148D01*
X1854676Y483939D01*
G01X1867076Y496856D02*
X1865836Y496439D01*
X1864906Y495398D01*
X1864286Y494148D01*
X1863821Y492481D01*
X1863666Y490606D01*
X1863821Y488731D01*
X1864286Y487064D01*
X1864906Y485814D01*
X1865836Y484773D01*
X1867076Y484356D01*
X1868316Y484773D01*
X1869246Y485814D01*
X1869866Y487064D01*
X1870331Y488731D01*
X1870486Y490606D01*
X1870331Y492481D01*
X1869866Y494148D01*
X1869246Y495398D01*
X1868316Y496439D01*
X1867076Y496856D01*
G01X1826466Y542431D02*
X1827396Y541389D01*
X1828481Y540764D01*
X1829876Y540556D01*
X1831271Y540973D01*
X1832356Y541806D01*
X1833131Y543264D01*
X1833286Y544931D01*
X1832976Y546598D01*
X1832201Y547639D01*
X1831116Y548473D01*
X1830031Y548681D01*
X1828946Y548473D01*
X1827551Y547639D01*
X1828016Y553056D01*
X1832201D01*
G01X1842276D02*
X1841036Y552639D01*
X1840106Y551598D01*
X1839486Y550348D01*
X1839021Y548681D01*
X1838866Y546806D01*
X1839021Y544931D01*
X1839486Y543264D01*
X1840106Y542014D01*
X1841036Y540973D01*
X1842276Y540556D01*
X1843516Y540973D01*
X1844446Y542014D01*
X1845066Y543264D01*
X1845531Y544931D01*
X1845686Y546806D01*
X1845531Y548681D01*
X1845066Y550348D01*
X1844446Y551598D01*
X1843516Y552639D01*
X1842276Y553056D01*
G01X1854676Y540139D02*
X1854366Y540348D01*
Y540764D01*
X1854676Y540973D01*
X1854986Y540764D01*
Y540348D01*
X1854676Y540139D01*
G01X1867076Y553056D02*
X1865836Y552639D01*
X1864906Y551598D01*
X1864286Y550348D01*
X1863821Y548681D01*
X1863666Y546806D01*
X1863821Y544931D01*
X1864286Y543264D01*
X1864906Y542014D01*
X1865836Y540973D01*
X1867076Y540556D01*
X1868316Y540973D01*
X1869246Y542014D01*
X1869866Y543264D01*
X1870331Y544931D01*
X1870486Y546806D01*
X1870331Y548681D01*
X1869866Y550348D01*
X1869246Y551598D01*
X1868316Y552639D01*
X1867076Y553056D01*
G01X1831736Y568656D02*
Y581156D01*
X1826001Y572198D01*
X1833751D01*
G01X1839331Y579073D02*
X1840261Y580322D01*
X1841346Y580948D01*
X1842586Y581156D01*
X1844136Y580739D01*
X1845221Y579698D01*
X1845531Y578448D01*
X1845376Y577197D01*
X1844756Y576156D01*
X1841656Y574073D01*
X1840261Y572614D01*
X1839331Y570531D01*
X1839021Y568656D01*
X1845531D01*
G01X1854676Y568239D02*
X1854366Y568448D01*
Y568864D01*
X1854676Y569073D01*
X1854986Y568864D01*
Y568448D01*
X1854676Y568239D01*
G01X1867076Y581156D02*
X1865836Y580739D01*
X1864906Y579698D01*
X1864286Y578448D01*
X1863821Y576781D01*
X1863666Y574906D01*
X1863821Y573031D01*
X1864286Y571364D01*
X1864906Y570114D01*
X1865836Y569073D01*
X1867076Y568656D01*
X1868316Y569073D01*
X1869246Y570114D01*
X1869866Y571364D01*
X1870331Y573031D01*
X1870486Y574906D01*
X1870331Y576781D01*
X1869866Y578448D01*
X1869246Y579698D01*
X1868316Y580739D01*
X1867076Y581156D01*
G01X1831736Y596756D02*
Y609256D01*
X1826001Y600298D01*
X1833751D01*
G01X1842276Y609256D02*
X1841036Y608839D01*
X1840106Y607798D01*
X1839486Y606548D01*
X1839021Y604881D01*
X1838866Y603006D01*
X1839021Y601131D01*
X1839486Y599464D01*
X1840106Y598214D01*
X1841036Y597173D01*
X1842276Y596756D01*
X1843516Y597173D01*
X1844446Y598214D01*
X1845066Y599464D01*
X1845531Y601131D01*
X1845686Y603006D01*
X1845531Y604881D01*
X1845066Y606548D01*
X1844446Y607798D01*
X1843516Y608839D01*
X1842276Y609256D01*
G01X1854676Y596339D02*
X1854366Y596548D01*
Y596964D01*
X1854676Y597173D01*
X1854986Y596964D01*
Y596548D01*
X1854676Y596339D01*
G01X1867076Y609256D02*
X1865836Y608839D01*
X1864906Y607798D01*
X1864286Y606548D01*
X1863821Y604881D01*
X1863666Y603006D01*
X1863821Y601131D01*
X1864286Y599464D01*
X1864906Y598214D01*
X1865836Y597173D01*
X1867076Y596756D01*
X1868316Y597173D01*
X1869246Y598214D01*
X1869866Y599464D01*
X1870331Y601131D01*
X1870486Y603006D01*
X1870331Y604881D01*
X1869866Y606548D01*
X1869246Y607798D01*
X1868316Y608839D01*
X1867076Y609256D01*
G01X1826466Y627356D02*
X1827396Y625897D01*
X1828636Y625064D01*
X1830031Y624856D01*
X1831271Y625064D01*
X1832511Y626106D01*
X1833286Y627356D01*
X1833441Y628606D01*
X1833131Y630064D01*
X1832046Y631106D01*
X1830961Y631523D01*
X1829566D01*
G01X1830961D02*
X1831891Y632148D01*
X1832666Y633189D01*
X1832976Y634439D01*
X1832666Y635689D01*
X1831891Y636731D01*
X1830496Y637356D01*
X1829101Y637148D01*
X1827706Y636314D01*
G01X1842276Y624856D02*
X1843361Y625064D01*
X1844601Y625689D01*
X1845376Y626731D01*
X1845686Y628189D01*
X1845376Y629647D01*
X1844446Y630898D01*
X1843051Y631523D01*
X1841501D01*
X1840571Y631939D01*
X1839796Y632981D01*
X1839486Y634439D01*
X1839951Y635898D01*
X1841036Y636939D01*
X1842276Y637356D01*
X1843516Y636939D01*
X1844601Y635898D01*
X1845066Y634439D01*
X1844756Y632981D01*
X1843981Y631939D01*
X1843051Y631523D01*
X1841501D01*
X1840106Y630898D01*
X1839176Y629647D01*
X1838866Y628189D01*
X1839176Y626731D01*
X1839951Y625689D01*
X1841191Y625064D01*
X1842276Y624856D01*
G01X1854676Y624439D02*
X1854366Y624648D01*
Y625064D01*
X1854676Y625273D01*
X1854986Y625064D01*
Y624648D01*
X1854676Y624439D01*
G01X1867076Y637356D02*
X1865836Y636939D01*
X1864906Y635898D01*
X1864286Y634648D01*
X1863821Y632981D01*
X1863666Y631106D01*
X1863821Y629231D01*
X1864286Y627564D01*
X1864906Y626314D01*
X1865836Y625273D01*
X1867076Y624856D01*
X1868316Y625273D01*
X1869246Y626314D01*
X1869866Y627564D01*
X1870331Y629231D01*
X1870486Y631106D01*
X1870331Y632981D01*
X1869866Y634648D01*
X1869246Y635898D01*
X1868316Y636939D01*
X1867076Y637356D01*
G01X1826466Y683556D02*
X1827396Y682097D01*
X1828636Y681264D01*
X1830031Y681056D01*
X1831271Y681264D01*
X1832511Y682306D01*
X1833286Y683556D01*
X1833441Y684806D01*
X1833131Y686264D01*
X1832046Y687306D01*
X1830961Y687723D01*
X1829566D01*
G01X1830961D02*
X1831891Y688348D01*
X1832666Y689389D01*
X1832976Y690639D01*
X1832666Y691889D01*
X1831891Y692931D01*
X1830496Y693556D01*
X1829101Y693348D01*
X1827706Y692514D01*
G01X1838866Y682931D02*
X1839796Y681889D01*
X1840881Y681264D01*
X1842276Y681056D01*
X1843671Y681473D01*
X1844756Y682306D01*
X1845531Y683764D01*
X1845686Y685431D01*
X1845376Y687098D01*
X1844601Y688139D01*
X1843516Y688973D01*
X1842431Y689181D01*
X1841346Y688973D01*
X1839951Y688139D01*
X1840416Y693556D01*
X1844601D01*
G01X1854676Y680639D02*
X1854366Y680848D01*
Y681264D01*
X1854676Y681473D01*
X1854986Y681264D01*
Y680848D01*
X1854676Y680639D01*
G01X1867076Y693556D02*
X1865836Y693139D01*
X1864906Y692098D01*
X1864286Y690848D01*
X1863821Y689181D01*
X1863666Y687306D01*
X1863821Y685431D01*
X1864286Y683764D01*
X1864906Y682514D01*
X1865836Y681473D01*
X1867076Y681056D01*
X1868316Y681473D01*
X1869246Y682514D01*
X1869866Y683764D01*
X1870331Y685431D01*
X1870486Y687306D01*
X1870331Y689181D01*
X1869866Y690848D01*
X1869246Y692098D01*
X1868316Y693139D01*
X1867076Y693556D01*
G01X1826466Y655456D02*
X1827396Y653997D01*
X1828636Y653164D01*
X1830031Y652956D01*
X1831271Y653164D01*
X1832511Y654206D01*
X1833286Y655456D01*
X1833441Y656706D01*
X1833131Y658164D01*
X1832046Y659206D01*
X1830961Y659623D01*
X1829566D01*
G01X1830961D02*
X1831891Y660248D01*
X1832666Y661289D01*
X1832976Y662539D01*
X1832666Y663789D01*
X1831891Y664831D01*
X1830496Y665456D01*
X1829101Y665248D01*
X1827706Y664414D01*
G01X1839331Y658164D02*
X1840416Y659623D01*
X1841346Y660456D01*
X1842586Y660873D01*
X1843671Y660456D01*
X1844446Y659623D01*
X1845066Y658373D01*
X1845221Y656914D01*
X1845066Y655664D01*
X1844446Y654414D01*
X1843516Y653373D01*
X1842431Y652956D01*
X1841191Y653373D01*
X1840106Y654622D01*
X1839486Y656498D01*
X1839331Y658581D01*
X1839641Y661289D01*
X1840106Y662748D01*
X1840881Y664206D01*
X1841966Y665248D01*
X1843051Y665456D01*
X1844136Y665039D01*
X1844911Y663998D01*
G01X1854676Y652539D02*
X1854366Y652748D01*
Y653164D01*
X1854676Y653373D01*
X1854986Y653164D01*
Y652748D01*
X1854676Y652539D01*
G01X1867076Y665456D02*
X1865836Y665039D01*
X1864906Y663998D01*
X1864286Y662748D01*
X1863821Y661081D01*
X1863666Y659206D01*
X1863821Y657331D01*
X1864286Y655664D01*
X1864906Y654414D01*
X1865836Y653373D01*
X1867076Y652956D01*
X1868316Y653373D01*
X1869246Y654414D01*
X1869866Y655664D01*
X1870331Y657331D01*
X1870486Y659206D01*
X1870331Y661081D01*
X1869866Y662748D01*
X1869246Y663998D01*
X1868316Y665039D01*
X1867076Y665456D01*
G01X1826466Y711656D02*
X1827396Y710197D01*
X1828636Y709364D01*
X1830031Y709156D01*
X1831271Y709364D01*
X1832511Y710406D01*
X1833286Y711656D01*
X1833441Y712906D01*
X1833131Y714364D01*
X1832046Y715406D01*
X1830961Y715823D01*
X1829566D01*
G01X1830961D02*
X1831891Y716448D01*
X1832666Y717489D01*
X1832976Y718739D01*
X1832666Y719989D01*
X1831891Y721031D01*
X1830496Y721656D01*
X1829101Y721448D01*
X1827706Y720614D01*
G01X1842276Y721656D02*
X1841036Y721239D01*
X1840106Y720198D01*
X1839486Y718948D01*
X1839021Y717281D01*
X1838866Y715406D01*
X1839021Y713531D01*
X1839486Y711864D01*
X1840106Y710614D01*
X1841036Y709573D01*
X1842276Y709156D01*
X1843516Y709573D01*
X1844446Y710614D01*
X1845066Y711864D01*
X1845531Y713531D01*
X1845686Y715406D01*
X1845531Y717281D01*
X1845066Y718948D01*
X1844446Y720198D01*
X1843516Y721239D01*
X1842276Y721656D01*
G01X1854676Y708739D02*
X1854366Y708948D01*
Y709364D01*
X1854676Y709573D01*
X1854986Y709364D01*
Y708948D01*
X1854676Y708739D01*
G01X1867076Y721656D02*
X1865836Y721239D01*
X1864906Y720198D01*
X1864286Y718948D01*
X1863821Y717281D01*
X1863666Y715406D01*
X1863821Y713531D01*
X1864286Y711864D01*
X1864906Y710614D01*
X1865836Y709573D01*
X1867076Y709156D01*
X1868316Y709573D01*
X1869246Y710614D01*
X1869866Y711864D01*
X1870331Y713531D01*
X1870486Y715406D01*
X1870331Y717281D01*
X1869866Y718948D01*
X1869246Y720198D01*
X1868316Y721239D01*
X1867076Y721656D01*
G01X1820731Y747673D02*
X1821661Y748922D01*
X1822746Y749548D01*
X1823986Y749756D01*
X1825536Y749339D01*
X1826621Y748298D01*
X1826931Y747048D01*
X1826776Y745797D01*
X1826156Y744756D01*
X1823056Y742673D01*
X1821661Y741214D01*
X1820731Y739131D01*
X1820421Y737256D01*
X1826931D01*
G01X1833131Y747673D02*
X1834061Y748922D01*
X1835146Y749548D01*
X1836386Y749756D01*
X1837936Y749339D01*
X1839021Y748298D01*
X1839331Y747048D01*
X1839176Y745797D01*
X1838556Y744756D01*
X1835456Y742673D01*
X1834061Y741214D01*
X1833131Y739131D01*
X1832821Y737256D01*
X1839331D01*
G01X1848476Y736839D02*
X1848166Y737048D01*
Y737464D01*
X1848476Y737673D01*
X1848786Y737464D01*
Y737048D01*
X1848476Y736839D01*
G01X1862736Y737256D02*
Y749756D01*
X1857001Y740798D01*
X1864751D01*
G01X1875136Y737256D02*
Y749756D01*
X1869401Y740798D01*
X1877151D01*
G01X1829876Y765356D02*
Y777856D01*
X1828016Y775356D01*
G01Y765356D02*
X1831736D01*
G01X1839331Y770564D02*
X1840416Y772023D01*
X1841346Y772856D01*
X1842586Y773273D01*
X1843671Y772856D01*
X1844446Y772023D01*
X1845066Y770773D01*
X1845221Y769314D01*
X1845066Y768064D01*
X1844446Y766814D01*
X1843516Y765773D01*
X1842431Y765356D01*
X1841191Y765773D01*
X1840106Y767022D01*
X1839486Y768898D01*
X1839331Y770981D01*
X1839641Y773689D01*
X1840106Y775148D01*
X1840881Y776606D01*
X1841966Y777648D01*
X1843051Y777856D01*
X1844136Y777439D01*
X1844911Y776398D01*
G01X1854676Y764939D02*
X1854366Y765148D01*
Y765564D01*
X1854676Y765773D01*
X1854986Y765564D01*
Y765148D01*
X1854676Y764939D01*
G01X1867076Y777856D02*
X1865836Y777439D01*
X1864906Y776398D01*
X1864286Y775148D01*
X1863821Y773481D01*
X1863666Y771606D01*
X1863821Y769731D01*
X1864286Y768064D01*
X1864906Y766814D01*
X1865836Y765773D01*
X1867076Y765356D01*
X1868316Y765773D01*
X1869246Y766814D01*
X1869866Y768064D01*
X1870331Y769731D01*
X1870486Y771606D01*
X1870331Y773481D01*
X1869866Y775148D01*
X1869246Y776398D01*
X1868316Y777439D01*
X1867076Y777856D01*
G01X1823676Y793456D02*
Y805956D01*
X1821816Y803456D01*
G01Y793456D02*
X1825536D01*
G01X1837936D02*
Y805956D01*
X1832201Y796998D01*
X1839951D01*
G01X1848476Y793039D02*
X1848166Y793248D01*
Y793664D01*
X1848476Y793873D01*
X1848786Y793664D01*
Y793248D01*
X1848476Y793039D01*
G01X1857466Y795331D02*
X1858396Y794289D01*
X1859481Y793664D01*
X1860876Y793456D01*
X1862271Y793873D01*
X1863356Y794706D01*
X1864131Y796164D01*
X1864286Y797831D01*
X1863976Y799498D01*
X1863201Y800539D01*
X1862116Y801373D01*
X1861031Y801581D01*
X1859946Y801373D01*
X1858551Y800539D01*
X1859016Y805956D01*
X1863201D01*
G01X1870331Y798664D02*
X1871416Y800123D01*
X1872346Y800956D01*
X1873586Y801373D01*
X1874671Y800956D01*
X1875446Y800123D01*
X1876066Y798873D01*
X1876221Y797414D01*
X1876066Y796164D01*
X1875446Y794914D01*
X1874516Y793873D01*
X1873431Y793456D01*
X1872191Y793873D01*
X1871106Y795122D01*
X1870486Y796998D01*
X1870331Y799081D01*
X1870641Y801789D01*
X1871106Y803248D01*
X1871881Y804706D01*
X1872966Y805748D01*
X1874051Y805956D01*
X1875136Y805539D01*
X1875911Y804498D01*
G01X1829876Y849656D02*
Y862156D01*
X1828016Y859656D01*
G01Y849656D02*
X1831736D01*
G01X1842276Y862156D02*
X1841036Y861739D01*
X1840106Y860698D01*
X1839486Y859448D01*
X1839021Y857781D01*
X1838866Y855906D01*
X1839021Y854031D01*
X1839486Y852364D01*
X1840106Y851114D01*
X1841036Y850073D01*
X1842276Y849656D01*
X1843516Y850073D01*
X1844446Y851114D01*
X1845066Y852364D01*
X1845531Y854031D01*
X1845686Y855906D01*
X1845531Y857781D01*
X1845066Y859448D01*
X1844446Y860698D01*
X1843516Y861739D01*
X1842276Y862156D01*
G01X1854676Y849239D02*
X1854366Y849448D01*
Y849864D01*
X1854676Y850073D01*
X1854986Y849864D01*
Y849448D01*
X1854676Y849239D01*
G01X1867076Y862156D02*
X1865836Y861739D01*
X1864906Y860698D01*
X1864286Y859448D01*
X1863821Y857781D01*
X1863666Y855906D01*
X1863821Y854031D01*
X1864286Y852364D01*
X1864906Y851114D01*
X1865836Y850073D01*
X1867076Y849656D01*
X1868316Y850073D01*
X1869246Y851114D01*
X1869866Y852364D01*
X1870331Y854031D01*
X1870486Y855906D01*
X1870331Y857781D01*
X1869866Y859448D01*
X1869246Y860698D01*
X1868316Y861739D01*
X1867076Y862156D01*
G01X1829876Y821556D02*
Y834056D01*
X1828016Y831556D01*
G01Y821556D02*
X1831736D01*
G01X1839331Y831973D02*
X1840261Y833222D01*
X1841346Y833848D01*
X1842586Y834056D01*
X1844136Y833639D01*
X1845221Y832598D01*
X1845531Y831348D01*
X1845376Y830097D01*
X1844756Y829056D01*
X1841656Y826973D01*
X1840261Y825514D01*
X1839331Y823431D01*
X1839021Y821556D01*
X1845531D01*
G01X1854676Y821139D02*
X1854366Y821348D01*
Y821764D01*
X1854676Y821973D01*
X1854986Y821764D01*
Y821348D01*
X1854676Y821139D01*
G01X1867076Y834056D02*
X1865836Y833639D01*
X1864906Y832598D01*
X1864286Y831348D01*
X1863821Y829681D01*
X1863666Y827806D01*
X1863821Y825931D01*
X1864286Y824264D01*
X1864906Y823014D01*
X1865836Y821973D01*
X1867076Y821556D01*
X1868316Y821973D01*
X1869246Y823014D01*
X1869866Y824264D01*
X1870331Y825931D01*
X1870486Y827806D01*
X1870331Y829681D01*
X1869866Y831348D01*
X1869246Y832598D01*
X1868316Y833639D01*
X1867076Y834056D01*
G01X1836076Y877756D02*
X1837161Y877964D01*
X1838401Y878589D01*
X1839176Y879631D01*
X1839486Y881089D01*
X1839176Y882547D01*
X1838246Y883798D01*
X1836851Y884423D01*
X1835301D01*
X1834371Y884839D01*
X1833596Y885881D01*
X1833286Y887339D01*
X1833751Y888798D01*
X1834836Y889839D01*
X1836076Y890256D01*
X1837316Y889839D01*
X1838401Y888798D01*
X1838866Y887339D01*
X1838556Y885881D01*
X1837781Y884839D01*
X1836851Y884423D01*
X1835301D01*
X1833906Y883798D01*
X1832976Y882547D01*
X1832666Y881089D01*
X1832976Y879631D01*
X1833751Y878589D01*
X1834991Y877964D01*
X1836076Y877756D01*
G01X1848476Y877339D02*
X1848166Y877548D01*
Y877964D01*
X1848476Y878173D01*
X1848786Y877964D01*
Y877548D01*
X1848476Y877339D01*
G01X1860876Y890256D02*
X1859636Y889839D01*
X1858706Y888798D01*
X1858086Y887548D01*
X1857621Y885881D01*
X1857466Y884006D01*
X1857621Y882131D01*
X1858086Y880464D01*
X1858706Y879214D01*
X1859636Y878173D01*
X1860876Y877756D01*
X1862116Y878173D01*
X1863046Y879214D01*
X1863666Y880464D01*
X1864131Y882131D01*
X1864286Y884006D01*
X1864131Y885881D01*
X1863666Y887548D01*
X1863046Y888798D01*
X1862116Y889839D01*
X1860876Y890256D01*
G01X1826621Y909072D02*
X1827861Y908031D01*
X1829256Y907406D01*
X1830496D01*
X1831736Y908031D01*
X1832666Y909072D01*
X1833131Y910531D01*
X1832821Y911989D01*
X1832046Y913239D01*
X1830651Y914073D01*
X1828791Y914489D01*
X1827706Y915323D01*
X1827241Y916781D01*
X1827551Y918239D01*
X1828326Y919281D01*
X1829411Y919906D01*
X1830496D01*
X1831581Y919489D01*
X1832511Y918448D01*
G01X1840416Y919906D02*
X1844136D01*
G01X1842276D02*
Y907406D01*
G01X1840416D02*
X1844136D01*
G01X1851731Y919906D02*
X1857621D01*
X1851731Y907406D01*
X1857621D01*
G01X1870176D02*
X1863976D01*
Y919906D01*
X1870176D01*
G01X1867696Y913864D02*
X1863976D01*
G01X1947211Y231456D02*
Y243956D01*
X1954341Y231456D01*
Y243956D01*
G01X1963176Y231456D02*
X1961936Y231664D01*
X1960851Y232497D01*
X1959921Y233748D01*
X1959301Y235206D01*
X1958991Y236873D01*
Y238539D01*
X1959301Y240206D01*
X1959921Y241664D01*
X1960851Y242914D01*
X1961936Y243748D01*
X1963176Y243956D01*
X1964416Y243748D01*
X1965501Y242914D01*
X1966431Y241664D01*
X1967051Y240206D01*
X1967361Y238539D01*
Y236873D01*
X1967051Y235206D01*
X1966431Y233748D01*
X1965501Y232497D01*
X1964416Y231664D01*
X1963176Y231456D01*
G01X1972011D02*
Y243956D01*
X1979141Y231456D01*
Y243956D01*
G01X1985961Y235623D02*
X1989991D01*
G01X1997276Y231456D02*
Y243956D01*
X2000996D01*
X2002236Y243331D01*
X2003166Y241873D01*
X2003476Y240206D01*
X2003166Y238539D01*
X2002391Y237289D01*
X2000996Y236664D01*
X1997276D01*
G01X2009676Y243956D02*
Y231456D01*
X2015876D01*
G01X2021301D02*
X2025176Y243956D01*
X2029051Y231456D01*
G01X2027656Y235831D02*
X2022696D01*
G01X2037576Y243956D02*
Y231456D01*
G01X2034011Y243956D02*
X2041141D01*
G01X2053076Y231456D02*
X2046876D01*
Y243956D01*
X2053076D01*
G01X2050596Y237914D02*
X2046876D01*
G01X2058966Y231456D02*
Y243956D01*
X2062066D01*
X2063306Y243331D01*
X2064236Y242498D01*
X2065011Y241248D01*
X2065631Y239789D01*
X2065786Y237706D01*
X2065631Y235623D01*
X2065011Y234164D01*
X2064236Y232914D01*
X2063306Y232081D01*
X2062066Y231456D01*
X2058966D01*
G01X1943026Y926156D02*
Y223656D01*
G01X1947211Y259556D02*
Y272056D01*
X1954341Y259556D01*
Y272056D01*
G01X1963176Y259556D02*
X1961936Y259764D01*
X1960851Y260597D01*
X1959921Y261848D01*
X1959301Y263306D01*
X1958991Y264973D01*
Y266639D01*
X1959301Y268306D01*
X1959921Y269764D01*
X1960851Y271014D01*
X1961936Y271848D01*
X1963176Y272056D01*
X1964416Y271848D01*
X1965501Y271014D01*
X1966431Y269764D01*
X1967051Y268306D01*
X1967361Y266639D01*
Y264973D01*
X1967051Y263306D01*
X1966431Y261848D01*
X1965501Y260597D01*
X1964416Y259764D01*
X1963176Y259556D01*
G01X1972011D02*
Y272056D01*
X1979141Y259556D01*
Y272056D01*
G01X1985961Y263723D02*
X1989991D01*
G01X1997276Y259556D02*
Y272056D01*
X2000996D01*
X2002236Y271431D01*
X2003166Y269973D01*
X2003476Y268306D01*
X2003166Y266639D01*
X2002391Y265389D01*
X2000996Y264764D01*
X1997276D01*
G01X2009676Y272056D02*
Y259556D01*
X2015876D01*
G01X2021301D02*
X2025176Y272056D01*
X2029051Y259556D01*
G01X2027656Y263931D02*
X2022696D01*
G01X2037576Y272056D02*
Y259556D01*
G01X2034011Y272056D02*
X2041141D01*
G01X2053076Y259556D02*
X2046876D01*
Y272056D01*
X2053076D01*
G01X2050596Y266014D02*
X2046876D01*
G01X2058966Y259556D02*
Y272056D01*
X2062066D01*
X2063306Y271431D01*
X2064236Y270598D01*
X2065011Y269348D01*
X2065631Y267889D01*
X2065786Y265806D01*
X2065631Y263723D01*
X2065011Y262264D01*
X2064236Y261014D01*
X2063306Y260181D01*
X2062066Y259556D01*
X2058966D01*
G01X1947211Y287656D02*
Y300156D01*
X1954341Y287656D01*
Y300156D01*
G01X1963176Y287656D02*
X1961936Y287864D01*
X1960851Y288697D01*
X1959921Y289948D01*
X1959301Y291406D01*
X1958991Y293073D01*
Y294739D01*
X1959301Y296406D01*
X1959921Y297864D01*
X1960851Y299114D01*
X1961936Y299948D01*
X1963176Y300156D01*
X1964416Y299948D01*
X1965501Y299114D01*
X1966431Y297864D01*
X1967051Y296406D01*
X1967361Y294739D01*
Y293073D01*
X1967051Y291406D01*
X1966431Y289948D01*
X1965501Y288697D01*
X1964416Y287864D01*
X1963176Y287656D01*
G01X1972011D02*
Y300156D01*
X1979141Y287656D01*
Y300156D01*
G01X1985961Y291823D02*
X1989991D01*
G01X1997276Y287656D02*
Y300156D01*
X2000996D01*
X2002236Y299531D01*
X2003166Y298073D01*
X2003476Y296406D01*
X2003166Y294739D01*
X2002391Y293489D01*
X2000996Y292864D01*
X1997276D01*
G01X2009676Y300156D02*
Y287656D01*
X2015876D01*
G01X2021301D02*
X2025176Y300156D01*
X2029051Y287656D01*
G01X2027656Y292031D02*
X2022696D01*
G01X2037576Y300156D02*
Y287656D01*
G01X2034011Y300156D02*
X2041141D01*
G01X2053076Y287656D02*
X2046876D01*
Y300156D01*
X2053076D01*
G01X2050596Y294114D02*
X2046876D01*
G01X2058966Y287656D02*
Y300156D01*
X2062066D01*
X2063306Y299531D01*
X2064236Y298698D01*
X2065011Y297448D01*
X2065631Y295989D01*
X2065786Y293906D01*
X2065631Y291823D01*
X2065011Y290364D01*
X2064236Y289114D01*
X2063306Y288281D01*
X2062066Y287656D01*
X2058966D01*
G01X1947211Y343856D02*
Y356356D01*
X1954341Y343856D01*
Y356356D01*
G01X1963176Y343856D02*
X1961936Y344064D01*
X1960851Y344897D01*
X1959921Y346148D01*
X1959301Y347606D01*
X1958991Y349273D01*
Y350939D01*
X1959301Y352606D01*
X1959921Y354064D01*
X1960851Y355314D01*
X1961936Y356148D01*
X1963176Y356356D01*
X1964416Y356148D01*
X1965501Y355314D01*
X1966431Y354064D01*
X1967051Y352606D01*
X1967361Y350939D01*
Y349273D01*
X1967051Y347606D01*
X1966431Y346148D01*
X1965501Y344897D01*
X1964416Y344064D01*
X1963176Y343856D01*
G01X1972011D02*
Y356356D01*
X1979141Y343856D01*
Y356356D01*
G01X1985961Y348023D02*
X1989991D01*
G01X1997276Y343856D02*
Y356356D01*
X2000996D01*
X2002236Y355731D01*
X2003166Y354273D01*
X2003476Y352606D01*
X2003166Y350939D01*
X2002391Y349689D01*
X2000996Y349064D01*
X1997276D01*
G01X2009676Y356356D02*
Y343856D01*
X2015876D01*
G01X2021301D02*
X2025176Y356356D01*
X2029051Y343856D01*
G01X2027656Y348231D02*
X2022696D01*
G01X2037576Y356356D02*
Y343856D01*
G01X2034011Y356356D02*
X2041141D01*
G01X2053076Y343856D02*
X2046876D01*
Y356356D01*
X2053076D01*
G01X2050596Y350314D02*
X2046876D01*
G01X2058966Y343856D02*
Y356356D01*
X2062066D01*
X2063306Y355731D01*
X2064236Y354898D01*
X2065011Y353648D01*
X2065631Y352189D01*
X2065786Y350106D01*
X2065631Y348023D01*
X2065011Y346564D01*
X2064236Y345314D01*
X2063306Y344481D01*
X2062066Y343856D01*
X2058966D01*
G01X1947211Y315756D02*
Y328256D01*
X1954341Y315756D01*
Y328256D01*
G01X1963176Y315756D02*
X1961936Y315964D01*
X1960851Y316797D01*
X1959921Y318048D01*
X1959301Y319506D01*
X1958991Y321173D01*
Y322839D01*
X1959301Y324506D01*
X1959921Y325964D01*
X1960851Y327214D01*
X1961936Y328048D01*
X1963176Y328256D01*
X1964416Y328048D01*
X1965501Y327214D01*
X1966431Y325964D01*
X1967051Y324506D01*
X1967361Y322839D01*
Y321173D01*
X1967051Y319506D01*
X1966431Y318048D01*
X1965501Y316797D01*
X1964416Y315964D01*
X1963176Y315756D01*
G01X1972011D02*
Y328256D01*
X1979141Y315756D01*
Y328256D01*
G01X1985961Y319923D02*
X1989991D01*
G01X1997276Y315756D02*
Y328256D01*
X2000996D01*
X2002236Y327631D01*
X2003166Y326173D01*
X2003476Y324506D01*
X2003166Y322839D01*
X2002391Y321589D01*
X2000996Y320964D01*
X1997276D01*
G01X2009676Y328256D02*
Y315756D01*
X2015876D01*
G01X2021301D02*
X2025176Y328256D01*
X2029051Y315756D01*
G01X2027656Y320131D02*
X2022696D01*
G01X2037576Y328256D02*
Y315756D01*
G01X2034011Y328256D02*
X2041141D01*
G01X2053076Y315756D02*
X2046876D01*
Y328256D01*
X2053076D01*
G01X2050596Y322214D02*
X2046876D01*
G01X2058966Y315756D02*
Y328256D01*
X2062066D01*
X2063306Y327631D01*
X2064236Y326798D01*
X2065011Y325548D01*
X2065631Y324089D01*
X2065786Y322006D01*
X2065631Y319923D01*
X2065011Y318464D01*
X2064236Y317214D01*
X2063306Y316381D01*
X2062066Y315756D01*
X2058966D01*
G01X1972476Y371956D02*
Y384456D01*
X1976196D01*
X1977436Y383831D01*
X1978366Y382373D01*
X1978676Y380706D01*
X1978366Y379039D01*
X1977591Y377789D01*
X1976196Y377164D01*
X1972476D01*
G01X1984876Y384456D02*
Y371956D01*
X1991076D01*
G01X1996501D02*
X2000376Y384456D01*
X2004251Y371956D01*
G01X2002856Y376331D02*
X1997896D01*
G01X2012776Y384456D02*
Y371956D01*
G01X2009211Y384456D02*
X2016341D01*
G01X2028276Y371956D02*
X2022076D01*
Y384456D01*
X2028276D01*
G01X2025796Y378414D02*
X2022076D01*
G01X2034166Y371956D02*
Y384456D01*
X2037266D01*
X2038506Y383831D01*
X2039436Y382998D01*
X2040211Y381748D01*
X2040831Y380289D01*
X2040986Y378206D01*
X2040831Y376123D01*
X2040211Y374664D01*
X2039436Y373414D01*
X2038506Y372581D01*
X2037266Y371956D01*
X2034166D01*
G01X1972476Y400056D02*
Y412556D01*
X1976196D01*
X1977436Y411931D01*
X1978366Y410473D01*
X1978676Y408806D01*
X1978366Y407139D01*
X1977591Y405889D01*
X1976196Y405264D01*
X1972476D01*
G01X1984876Y412556D02*
Y400056D01*
X1991076D01*
G01X1996501D02*
X2000376Y412556D01*
X2004251Y400056D01*
G01X2002856Y404431D02*
X1997896D01*
G01X2012776Y412556D02*
Y400056D01*
G01X2009211Y412556D02*
X2016341D01*
G01X2028276Y400056D02*
X2022076D01*
Y412556D01*
X2028276D01*
G01X2025796Y406514D02*
X2022076D01*
G01X2034166Y400056D02*
Y412556D01*
X2037266D01*
X2038506Y411931D01*
X2039436Y411098D01*
X2040211Y409848D01*
X2040831Y408389D01*
X2040986Y406306D01*
X2040831Y404223D01*
X2040211Y402764D01*
X2039436Y401514D01*
X2038506Y400681D01*
X2037266Y400056D01*
X2034166D01*
G01X1972476Y428156D02*
Y440656D01*
X1976196D01*
X1977436Y440031D01*
X1978366Y438573D01*
X1978676Y436906D01*
X1978366Y435239D01*
X1977591Y433989D01*
X1976196Y433364D01*
X1972476D01*
G01X1984876Y440656D02*
Y428156D01*
X1991076D01*
G01X1996501D02*
X2000376Y440656D01*
X2004251Y428156D01*
G01X2002856Y432531D02*
X1997896D01*
G01X2012776Y440656D02*
Y428156D01*
G01X2009211Y440656D02*
X2016341D01*
G01X2028276Y428156D02*
X2022076D01*
Y440656D01*
X2028276D01*
G01X2025796Y434614D02*
X2022076D01*
G01X2034166Y428156D02*
Y440656D01*
X2037266D01*
X2038506Y440031D01*
X2039436Y439198D01*
X2040211Y437948D01*
X2040831Y436489D01*
X2040986Y434406D01*
X2040831Y432323D01*
X2040211Y430864D01*
X2039436Y429614D01*
X2038506Y428781D01*
X2037266Y428156D01*
X2034166D01*
G01X1972476Y456256D02*
Y468756D01*
X1976196D01*
X1977436Y468131D01*
X1978366Y466673D01*
X1978676Y465006D01*
X1978366Y463339D01*
X1977591Y462089D01*
X1976196Y461464D01*
X1972476D01*
G01X1984876Y468756D02*
Y456256D01*
X1991076D01*
G01X1996501D02*
X2000376Y468756D01*
X2004251Y456256D01*
G01X2002856Y460631D02*
X1997896D01*
G01X2012776Y468756D02*
Y456256D01*
G01X2009211Y468756D02*
X2016341D01*
G01X2028276Y456256D02*
X2022076D01*
Y468756D01*
X2028276D01*
G01X2025796Y462714D02*
X2022076D01*
G01X2034166Y456256D02*
Y468756D01*
X2037266D01*
X2038506Y468131D01*
X2039436Y467298D01*
X2040211Y466048D01*
X2040831Y464589D01*
X2040986Y462506D01*
X2040831Y460423D01*
X2040211Y458964D01*
X2039436Y457714D01*
X2038506Y456881D01*
X2037266Y456256D01*
X2034166D01*
G01X1972476Y512456D02*
Y524956D01*
X1976196D01*
X1977436Y524331D01*
X1978366Y522873D01*
X1978676Y521206D01*
X1978366Y519539D01*
X1977591Y518289D01*
X1976196Y517664D01*
X1972476D01*
G01X1984876Y524956D02*
Y512456D01*
X1991076D01*
G01X1996501D02*
X2000376Y524956D01*
X2004251Y512456D01*
G01X2002856Y516831D02*
X1997896D01*
G01X2012776Y524956D02*
Y512456D01*
G01X2009211Y524956D02*
X2016341D01*
G01X2028276Y512456D02*
X2022076D01*
Y524956D01*
X2028276D01*
G01X2025796Y518914D02*
X2022076D01*
G01X2034166Y512456D02*
Y524956D01*
X2037266D01*
X2038506Y524331D01*
X2039436Y523498D01*
X2040211Y522248D01*
X2040831Y520789D01*
X2040986Y518706D01*
X2040831Y516623D01*
X2040211Y515164D01*
X2039436Y513914D01*
X2038506Y513081D01*
X2037266Y512456D01*
X2034166D01*
G01X1972476Y484356D02*
Y496856D01*
X1976196D01*
X1977436Y496231D01*
X1978366Y494773D01*
X1978676Y493106D01*
X1978366Y491439D01*
X1977591Y490189D01*
X1976196Y489564D01*
X1972476D01*
G01X1984876Y496856D02*
Y484356D01*
X1991076D01*
G01X1996501D02*
X2000376Y496856D01*
X2004251Y484356D01*
G01X2002856Y488731D02*
X1997896D01*
G01X2012776Y496856D02*
Y484356D01*
G01X2009211Y496856D02*
X2016341D01*
G01X2028276Y484356D02*
X2022076D01*
Y496856D01*
X2028276D01*
G01X2025796Y490814D02*
X2022076D01*
G01X2034166Y484356D02*
Y496856D01*
X2037266D01*
X2038506Y496231D01*
X2039436Y495398D01*
X2040211Y494148D01*
X2040831Y492689D01*
X2040986Y490606D01*
X2040831Y488523D01*
X2040211Y487064D01*
X2039436Y485814D01*
X2038506Y484981D01*
X2037266Y484356D01*
X2034166D01*
G01X1972476Y540556D02*
Y553056D01*
X1976196D01*
X1977436Y552431D01*
X1978366Y550973D01*
X1978676Y549306D01*
X1978366Y547639D01*
X1977591Y546389D01*
X1976196Y545764D01*
X1972476D01*
G01X1984876Y553056D02*
Y540556D01*
X1991076D01*
G01X1996501D02*
X2000376Y553056D01*
X2004251Y540556D01*
G01X2002856Y544931D02*
X1997896D01*
G01X2012776Y553056D02*
Y540556D01*
G01X2009211Y553056D02*
X2016341D01*
G01X2028276Y540556D02*
X2022076D01*
Y553056D01*
X2028276D01*
G01X2025796Y547014D02*
X2022076D01*
G01X2034166Y540556D02*
Y553056D01*
X2037266D01*
X2038506Y552431D01*
X2039436Y551598D01*
X2040211Y550348D01*
X2040831Y548889D01*
X2040986Y546806D01*
X2040831Y544723D01*
X2040211Y543264D01*
X2039436Y542014D01*
X2038506Y541181D01*
X2037266Y540556D01*
X2034166D01*
G01X1972476Y568656D02*
Y581156D01*
X1976196D01*
X1977436Y580531D01*
X1978366Y579073D01*
X1978676Y577406D01*
X1978366Y575739D01*
X1977591Y574489D01*
X1976196Y573864D01*
X1972476D01*
G01X1984876Y581156D02*
Y568656D01*
X1991076D01*
G01X1996501D02*
X2000376Y581156D01*
X2004251Y568656D01*
G01X2002856Y573031D02*
X1997896D01*
G01X2012776Y581156D02*
Y568656D01*
G01X2009211Y581156D02*
X2016341D01*
G01X2028276Y568656D02*
X2022076D01*
Y581156D01*
X2028276D01*
G01X2025796Y575114D02*
X2022076D01*
G01X2034166Y568656D02*
Y581156D01*
X2037266D01*
X2038506Y580531D01*
X2039436Y579698D01*
X2040211Y578448D01*
X2040831Y576989D01*
X2040986Y574906D01*
X2040831Y572823D01*
X2040211Y571364D01*
X2039436Y570114D01*
X2038506Y569281D01*
X2037266Y568656D01*
X2034166D01*
G01X1972476Y596756D02*
Y609256D01*
X1976196D01*
X1977436Y608631D01*
X1978366Y607173D01*
X1978676Y605506D01*
X1978366Y603839D01*
X1977591Y602589D01*
X1976196Y601964D01*
X1972476D01*
G01X1984876Y609256D02*
Y596756D01*
X1991076D01*
G01X1996501D02*
X2000376Y609256D01*
X2004251Y596756D01*
G01X2002856Y601131D02*
X1997896D01*
G01X2012776Y609256D02*
Y596756D01*
G01X2009211Y609256D02*
X2016341D01*
G01X2028276Y596756D02*
X2022076D01*
Y609256D01*
X2028276D01*
G01X2025796Y603214D02*
X2022076D01*
G01X2034166Y596756D02*
Y609256D01*
X2037266D01*
X2038506Y608631D01*
X2039436Y607798D01*
X2040211Y606548D01*
X2040831Y605089D01*
X2040986Y603006D01*
X2040831Y600923D01*
X2040211Y599464D01*
X2039436Y598214D01*
X2038506Y597381D01*
X2037266Y596756D01*
X2034166D01*
G01X1972476Y624856D02*
Y637356D01*
X1976196D01*
X1977436Y636731D01*
X1978366Y635273D01*
X1978676Y633606D01*
X1978366Y631939D01*
X1977591Y630689D01*
X1976196Y630064D01*
X1972476D01*
G01X1984876Y637356D02*
Y624856D01*
X1991076D01*
G01X1996501D02*
X2000376Y637356D01*
X2004251Y624856D01*
G01X2002856Y629231D02*
X1997896D01*
G01X2012776Y637356D02*
Y624856D01*
G01X2009211Y637356D02*
X2016341D01*
G01X2028276Y624856D02*
X2022076D01*
Y637356D01*
X2028276D01*
G01X2025796Y631314D02*
X2022076D01*
G01X2034166Y624856D02*
Y637356D01*
X2037266D01*
X2038506Y636731D01*
X2039436Y635898D01*
X2040211Y634648D01*
X2040831Y633189D01*
X2040986Y631106D01*
X2040831Y629023D01*
X2040211Y627564D01*
X2039436Y626314D01*
X2038506Y625481D01*
X2037266Y624856D01*
X2034166D01*
G01X1972476Y681056D02*
Y693556D01*
X1976196D01*
X1977436Y692931D01*
X1978366Y691473D01*
X1978676Y689806D01*
X1978366Y688139D01*
X1977591Y686889D01*
X1976196Y686264D01*
X1972476D01*
G01X1984876Y693556D02*
Y681056D01*
X1991076D01*
G01X1996501D02*
X2000376Y693556D01*
X2004251Y681056D01*
G01X2002856Y685431D02*
X1997896D01*
G01X2012776Y693556D02*
Y681056D01*
G01X2009211Y693556D02*
X2016341D01*
G01X2028276Y681056D02*
X2022076D01*
Y693556D01*
X2028276D01*
G01X2025796Y687514D02*
X2022076D01*
G01X2034166Y681056D02*
Y693556D01*
X2037266D01*
X2038506Y692931D01*
X2039436Y692098D01*
X2040211Y690848D01*
X2040831Y689389D01*
X2040986Y687306D01*
X2040831Y685223D01*
X2040211Y683764D01*
X2039436Y682514D01*
X2038506Y681681D01*
X2037266Y681056D01*
X2034166D01*
G01X1972476Y652956D02*
Y665456D01*
X1976196D01*
X1977436Y664831D01*
X1978366Y663373D01*
X1978676Y661706D01*
X1978366Y660039D01*
X1977591Y658789D01*
X1976196Y658164D01*
X1972476D01*
G01X1984876Y665456D02*
Y652956D01*
X1991076D01*
G01X1996501D02*
X2000376Y665456D01*
X2004251Y652956D01*
G01X2002856Y657331D02*
X1997896D01*
G01X2012776Y665456D02*
Y652956D01*
G01X2009211Y665456D02*
X2016341D01*
G01X2028276Y652956D02*
X2022076D01*
Y665456D01*
X2028276D01*
G01X2025796Y659414D02*
X2022076D01*
G01X2034166Y652956D02*
Y665456D01*
X2037266D01*
X2038506Y664831D01*
X2039436Y663998D01*
X2040211Y662748D01*
X2040831Y661289D01*
X2040986Y659206D01*
X2040831Y657123D01*
X2040211Y655664D01*
X2039436Y654414D01*
X2038506Y653581D01*
X2037266Y652956D01*
X2034166D01*
G01X1972476Y709156D02*
Y721656D01*
X1976196D01*
X1977436Y721031D01*
X1978366Y719573D01*
X1978676Y717906D01*
X1978366Y716239D01*
X1977591Y714989D01*
X1976196Y714364D01*
X1972476D01*
G01X1984876Y721656D02*
Y709156D01*
X1991076D01*
G01X1996501D02*
X2000376Y721656D01*
X2004251Y709156D01*
G01X2002856Y713531D02*
X1997896D01*
G01X2012776Y721656D02*
Y709156D01*
G01X2009211Y721656D02*
X2016341D01*
G01X2028276Y709156D02*
X2022076D01*
Y721656D01*
X2028276D01*
G01X2025796Y715614D02*
X2022076D01*
G01X2034166Y709156D02*
Y721656D01*
X2037266D01*
X2038506Y721031D01*
X2039436Y720198D01*
X2040211Y718948D01*
X2040831Y717489D01*
X2040986Y715406D01*
X2040831Y713323D01*
X2040211Y711864D01*
X2039436Y710614D01*
X2038506Y709781D01*
X2037266Y709156D01*
X2034166D01*
G01X1972476Y737256D02*
Y749756D01*
X1976196D01*
X1977436Y749131D01*
X1978366Y747673D01*
X1978676Y746006D01*
X1978366Y744339D01*
X1977591Y743089D01*
X1976196Y742464D01*
X1972476D01*
G01X1984876Y749756D02*
Y737256D01*
X1991076D01*
G01X1996501D02*
X2000376Y749756D01*
X2004251Y737256D01*
G01X2002856Y741631D02*
X1997896D01*
G01X2012776Y749756D02*
Y737256D01*
G01X2009211Y749756D02*
X2016341D01*
G01X2028276Y737256D02*
X2022076D01*
Y749756D01*
X2028276D01*
G01X2025796Y743714D02*
X2022076D01*
G01X2034166Y737256D02*
Y749756D01*
X2037266D01*
X2038506Y749131D01*
X2039436Y748298D01*
X2040211Y747048D01*
X2040831Y745589D01*
X2040986Y743506D01*
X2040831Y741423D01*
X2040211Y739964D01*
X2039436Y738714D01*
X2038506Y737881D01*
X2037266Y737256D01*
X2034166D01*
G01X1972476Y765356D02*
Y777856D01*
X1976196D01*
X1977436Y777231D01*
X1978366Y775773D01*
X1978676Y774106D01*
X1978366Y772439D01*
X1977591Y771189D01*
X1976196Y770564D01*
X1972476D01*
G01X1984876Y777856D02*
Y765356D01*
X1991076D01*
G01X1996501D02*
X2000376Y777856D01*
X2004251Y765356D01*
G01X2002856Y769731D02*
X1997896D01*
G01X2012776Y777856D02*
Y765356D01*
G01X2009211Y777856D02*
X2016341D01*
G01X2028276Y765356D02*
X2022076D01*
Y777856D01*
X2028276D01*
G01X2025796Y771814D02*
X2022076D01*
G01X2034166Y765356D02*
Y777856D01*
X2037266D01*
X2038506Y777231D01*
X2039436Y776398D01*
X2040211Y775148D01*
X2040831Y773689D01*
X2040986Y771606D01*
X2040831Y769523D01*
X2040211Y768064D01*
X2039436Y766814D01*
X2038506Y765981D01*
X2037266Y765356D01*
X2034166D01*
G01X1972476Y793456D02*
Y805956D01*
X1976196D01*
X1977436Y805331D01*
X1978366Y803873D01*
X1978676Y802206D01*
X1978366Y800539D01*
X1977591Y799289D01*
X1976196Y798664D01*
X1972476D01*
G01X1984876Y805956D02*
Y793456D01*
X1991076D01*
G01X1996501D02*
X2000376Y805956D01*
X2004251Y793456D01*
G01X2002856Y797831D02*
X1997896D01*
G01X2012776Y805956D02*
Y793456D01*
G01X2009211Y805956D02*
X2016341D01*
G01X2028276Y793456D02*
X2022076D01*
Y805956D01*
X2028276D01*
G01X2025796Y799914D02*
X2022076D01*
G01X2034166Y793456D02*
Y805956D01*
X2037266D01*
X2038506Y805331D01*
X2039436Y804498D01*
X2040211Y803248D01*
X2040831Y801789D01*
X2040986Y799706D01*
X2040831Y797623D01*
X2040211Y796164D01*
X2039436Y794914D01*
X2038506Y794081D01*
X2037266Y793456D01*
X2034166D01*
G01X1972476Y849656D02*
Y862156D01*
X1976196D01*
X1977436Y861531D01*
X1978366Y860073D01*
X1978676Y858406D01*
X1978366Y856739D01*
X1977591Y855489D01*
X1976196Y854864D01*
X1972476D01*
G01X1984876Y862156D02*
Y849656D01*
X1991076D01*
G01X1996501D02*
X2000376Y862156D01*
X2004251Y849656D01*
G01X2002856Y854031D02*
X1997896D01*
G01X2012776Y862156D02*
Y849656D01*
G01X2009211Y862156D02*
X2016341D01*
G01X2028276Y849656D02*
X2022076D01*
Y862156D01*
X2028276D01*
G01X2025796Y856114D02*
X2022076D01*
G01X2034166Y849656D02*
Y862156D01*
X2037266D01*
X2038506Y861531D01*
X2039436Y860698D01*
X2040211Y859448D01*
X2040831Y857989D01*
X2040986Y855906D01*
X2040831Y853823D01*
X2040211Y852364D01*
X2039436Y851114D01*
X2038506Y850281D01*
X2037266Y849656D01*
X2034166D01*
G01X1972476Y821556D02*
Y834056D01*
X1976196D01*
X1977436Y833431D01*
X1978366Y831973D01*
X1978676Y830306D01*
X1978366Y828639D01*
X1977591Y827389D01*
X1976196Y826764D01*
X1972476D01*
G01X1984876Y834056D02*
Y821556D01*
X1991076D01*
G01X1996501D02*
X2000376Y834056D01*
X2004251Y821556D01*
G01X2002856Y825931D02*
X1997896D01*
G01X2012776Y834056D02*
Y821556D01*
G01X2009211Y834056D02*
X2016341D01*
G01X2028276Y821556D02*
X2022076D01*
Y834056D01*
X2028276D01*
G01X2025796Y828014D02*
X2022076D01*
G01X2034166Y821556D02*
Y834056D01*
X2037266D01*
X2038506Y833431D01*
X2039436Y832598D01*
X2040211Y831348D01*
X2040831Y829889D01*
X2040986Y827806D01*
X2040831Y825723D01*
X2040211Y824264D01*
X2039436Y823014D01*
X2038506Y822181D01*
X2037266Y821556D01*
X2034166D01*
G01X1972476Y877756D02*
Y890256D01*
X1976196D01*
X1977436Y889631D01*
X1978366Y888173D01*
X1978676Y886506D01*
X1978366Y884839D01*
X1977591Y883589D01*
X1976196Y882964D01*
X1972476D01*
G01X1984876Y890256D02*
Y877756D01*
X1991076D01*
G01X1996501D02*
X2000376Y890256D01*
X2004251Y877756D01*
G01X2002856Y882131D02*
X1997896D01*
G01X2012776Y890256D02*
Y877756D01*
G01X2009211Y890256D02*
X2016341D01*
G01X2028276Y877756D02*
X2022076D01*
Y890256D01*
X2028276D01*
G01X2025796Y884214D02*
X2022076D01*
G01X2034166Y877756D02*
Y890256D01*
X2037266D01*
X2038506Y889631D01*
X2039436Y888798D01*
X2040211Y887548D01*
X2040831Y886089D01*
X2040986Y884006D01*
X2040831Y881923D01*
X2040211Y880464D01*
X2039436Y879214D01*
X2038506Y878381D01*
X2037266Y877756D01*
X2034166D01*
G01X1972476Y907406D02*
Y919906D01*
X1976196D01*
X1977436Y919281D01*
X1978366Y917823D01*
X1978676Y916156D01*
X1978366Y914489D01*
X1977591Y913239D01*
X1976196Y912614D01*
X1972476D01*
G01X1984876Y919906D02*
Y907406D01*
X1991076D01*
G01X1996501D02*
X2000376Y919906D01*
X2004251Y907406D01*
G01X2002856Y911781D02*
X1997896D01*
G01X2012776Y919906D02*
Y907406D01*
G01X2009211Y919906D02*
X2016341D01*
G01X2028276Y907406D02*
X2022076D01*
Y919906D01*
X2028276D01*
G01X2025796Y913864D02*
X2022076D01*
G01X2034166Y907406D02*
Y919906D01*
X2037266D01*
X2038506Y919281D01*
X2039436Y918448D01*
X2040211Y917198D01*
X2040831Y915739D01*
X2040986Y913656D01*
X2040831Y911573D01*
X2040211Y910114D01*
X2039436Y908864D01*
X2038506Y908031D01*
X2037266Y907406D01*
X2034166D01*
G01X2070126Y926156D02*
Y223656D01*
G01X2086866Y852156D02*
X2087796Y850697D01*
X2089036Y849864D01*
X2090431Y849656D01*
X2091671Y849864D01*
X2092911Y850906D01*
X2093686Y852156D01*
X2093841Y853406D01*
X2093531Y854864D01*
X2092446Y855906D01*
X2091361Y856323D01*
X2089966D01*
G01X2091361D02*
X2092291Y856948D01*
X2093066Y857989D01*
X2093376Y859239D01*
X2093066Y860489D01*
X2092291Y861531D01*
X2090896Y862156D01*
X2089501Y861948D01*
X2088106Y861114D01*
G01X2102676Y849656D02*
Y862156D01*
X2100816Y859656D01*
G01Y849656D02*
X2104536D01*
G01X2115076D02*
X2116161Y849864D01*
X2117401Y850489D01*
X2118176Y851531D01*
X2118486Y852989D01*
X2118176Y854447D01*
X2117246Y855698D01*
X2115851Y856323D01*
X2114301D01*
X2113371Y856739D01*
X2112596Y857781D01*
X2112286Y859239D01*
X2112751Y860698D01*
X2113836Y861739D01*
X2115076Y862156D01*
X2116316Y861739D01*
X2117401Y860698D01*
X2117866Y859239D01*
X2117556Y857781D01*
X2116781Y856739D01*
X2115851Y856323D01*
X2114301D01*
X2112906Y855698D01*
X2111976Y854447D01*
X2111666Y852989D01*
X2111976Y851531D01*
X2112751Y850489D01*
X2113991Y849864D01*
X2115076Y849656D01*
G01X2124066Y851531D02*
X2124996Y850489D01*
X2126081Y849864D01*
X2127476Y849656D01*
X2128871Y850073D01*
X2129956Y850906D01*
X2130731Y852364D01*
X2130886Y854031D01*
X2130576Y855698D01*
X2129801Y856739D01*
X2128716Y857573D01*
X2127631Y857781D01*
X2126546Y857573D01*
X2125151Y856739D01*
X2125616Y862156D01*
X2129801D01*
G01X2090276Y877756D02*
Y890256D01*
X2088416Y887756D01*
G01Y877756D02*
X2092136D01*
G01X2099731Y882964D02*
X2100816Y884423D01*
X2101746Y885256D01*
X2102986Y885673D01*
X2104071Y885256D01*
X2104846Y884423D01*
X2105466Y883173D01*
X2105621Y881714D01*
X2105466Y880464D01*
X2104846Y879214D01*
X2103916Y878173D01*
X2102831Y877756D01*
X2101591Y878173D01*
X2100506Y879422D01*
X2099886Y881298D01*
X2099731Y883381D01*
X2100041Y886089D01*
X2100506Y887548D01*
X2101281Y889006D01*
X2102366Y890048D01*
X2103451Y890256D01*
X2104536Y889839D01*
X2105311Y888798D01*
G01X2115076Y877756D02*
Y890256D01*
X2113216Y887756D01*
G01Y877756D02*
X2116936D01*
G01X2127476D02*
X2128561Y877964D01*
X2129801Y878589D01*
X2130576Y879631D01*
X2130886Y881089D01*
X2130576Y882547D01*
X2129646Y883798D01*
X2128251Y884423D01*
X2126701D01*
X2125771Y884839D01*
X2124996Y885881D01*
X2124686Y887339D01*
X2125151Y888798D01*
X2126236Y889839D01*
X2127476Y890256D01*
X2128716Y889839D01*
X2129801Y888798D01*
X2130266Y887339D01*
X2129956Y885881D01*
X2129181Y884839D01*
X2128251Y884423D01*
X2126701D01*
X2125306Y883798D01*
X2124376Y882547D01*
X2124066Y881089D01*
X2124376Y879631D01*
X2125151Y878589D01*
X2126391Y877964D01*
X2127476Y877756D01*
G01X2105931Y241873D02*
X2106861Y243122D01*
X2107946Y243748D01*
X2109186Y243956D01*
X2110736Y243539D01*
X2111821Y242498D01*
X2112131Y241248D01*
X2111976Y239997D01*
X2111356Y238956D01*
X2108256Y236873D01*
X2106861Y235414D01*
X2105931Y233331D01*
X2105621Y231456D01*
X2112131D01*
G01X2108876Y259556D02*
X2109961Y259764D01*
X2111201Y260389D01*
X2111976Y261431D01*
X2112286Y262889D01*
X2111976Y264347D01*
X2111046Y265598D01*
X2109651Y266223D01*
X2108101D01*
X2107171Y266639D01*
X2106396Y267681D01*
X2106086Y269139D01*
X2106551Y270598D01*
X2107636Y271639D01*
X2108876Y272056D01*
X2110116Y271639D01*
X2111201Y270598D01*
X2111666Y269139D01*
X2111356Y267681D01*
X2110581Y266639D01*
X2109651Y266223D01*
X2108101D01*
X2106706Y265598D01*
X2105776Y264347D01*
X2105466Y262889D01*
X2105776Y261431D01*
X2106551Y260389D01*
X2107791Y259764D01*
X2108876Y259556D01*
G01X2105931Y298073D02*
X2106861Y299322D01*
X2107946Y299948D01*
X2109186Y300156D01*
X2110736Y299739D01*
X2111821Y298698D01*
X2112131Y297448D01*
X2111976Y296197D01*
X2111356Y295156D01*
X2108256Y293073D01*
X2106861Y291614D01*
X2105931Y289531D01*
X2105621Y287656D01*
X2112131D01*
G01X2110736Y343856D02*
Y356356D01*
X2105001Y347398D01*
X2112751D01*
G01X2105931Y326173D02*
X2106861Y327422D01*
X2107946Y328048D01*
X2109186Y328256D01*
X2110736Y327839D01*
X2111821Y326798D01*
X2112131Y325548D01*
X2111976Y324297D01*
X2111356Y323256D01*
X2108256Y321173D01*
X2106861Y319714D01*
X2105931Y317631D01*
X2105621Y315756D01*
X2112131D01*
G01X2108876Y371956D02*
Y384456D01*
X2107016Y381956D01*
G01Y371956D02*
X2110736D01*
G01X2105466Y402556D02*
X2106396Y401097D01*
X2107636Y400264D01*
X2109031Y400056D01*
X2110271Y400264D01*
X2111511Y401306D01*
X2112286Y402556D01*
X2112441Y403806D01*
X2112131Y405264D01*
X2111046Y406306D01*
X2109961Y406723D01*
X2108566D01*
G01X2109961D02*
X2110891Y407348D01*
X2111666Y408389D01*
X2111976Y409639D01*
X2111666Y410889D01*
X2110891Y411931D01*
X2109496Y412556D01*
X2108101Y412348D01*
X2106706Y411514D01*
G01X2108876Y428156D02*
X2109961Y428364D01*
X2111201Y428989D01*
X2111976Y430031D01*
X2112286Y431489D01*
X2111976Y432947D01*
X2111046Y434198D01*
X2109651Y434823D01*
X2108101D01*
X2107171Y435239D01*
X2106396Y436281D01*
X2106086Y437739D01*
X2106551Y439198D01*
X2107636Y440239D01*
X2108876Y440656D01*
X2110116Y440239D01*
X2111201Y439198D01*
X2111666Y437739D01*
X2111356Y436281D01*
X2110581Y435239D01*
X2109651Y434823D01*
X2108101D01*
X2106706Y434198D01*
X2105776Y432947D01*
X2105466Y431489D01*
X2105776Y430031D01*
X2106551Y428989D01*
X2107791Y428364D01*
X2108876Y428156D01*
G01X2105931Y466673D02*
X2106861Y467922D01*
X2107946Y468548D01*
X2109186Y468756D01*
X2110736Y468339D01*
X2111821Y467298D01*
X2112131Y466048D01*
X2111976Y464797D01*
X2111356Y463756D01*
X2108256Y461673D01*
X2106861Y460214D01*
X2105931Y458131D01*
X2105621Y456256D01*
X2112131D01*
G01X2105931Y522873D02*
X2106861Y524122D01*
X2107946Y524748D01*
X2109186Y524956D01*
X2110736Y524539D01*
X2111821Y523498D01*
X2112131Y522248D01*
X2111976Y520997D01*
X2111356Y519956D01*
X2108256Y517873D01*
X2106861Y516414D01*
X2105931Y514331D01*
X2105621Y512456D01*
X2112131D01*
G01X2108876Y484356D02*
X2109961Y484564D01*
X2111201Y485189D01*
X2111976Y486231D01*
X2112286Y487689D01*
X2111976Y489147D01*
X2111046Y490398D01*
X2109651Y491023D01*
X2108101D01*
X2107171Y491439D01*
X2106396Y492481D01*
X2106086Y493939D01*
X2106551Y495398D01*
X2107636Y496439D01*
X2108876Y496856D01*
X2110116Y496439D01*
X2111201Y495398D01*
X2111666Y493939D01*
X2111356Y492481D01*
X2110581Y491439D01*
X2109651Y491023D01*
X2108101D01*
X2106706Y490398D01*
X2105776Y489147D01*
X2105466Y487689D01*
X2105776Y486231D01*
X2106551Y485189D01*
X2107791Y484564D01*
X2108876Y484356D01*
G01X2105466Y542431D02*
X2106396Y541389D01*
X2107481Y540764D01*
X2108876Y540556D01*
X2110271Y540973D01*
X2111356Y541806D01*
X2112131Y543264D01*
X2112286Y544931D01*
X2111976Y546598D01*
X2111201Y547639D01*
X2110116Y548473D01*
X2109031Y548681D01*
X2107946Y548473D01*
X2106551Y547639D01*
X2107016Y553056D01*
X2111201D01*
G01X2105466Y571156D02*
X2106396Y569697D01*
X2107636Y568864D01*
X2109031Y568656D01*
X2110271Y568864D01*
X2111511Y569906D01*
X2112286Y571156D01*
X2112441Y572406D01*
X2112131Y573864D01*
X2111046Y574906D01*
X2109961Y575323D01*
X2108566D01*
G01X2109961D02*
X2110891Y575948D01*
X2111666Y576989D01*
X2111976Y578239D01*
X2111666Y579489D01*
X2110891Y580531D01*
X2109496Y581156D01*
X2108101Y580948D01*
X2106706Y580114D01*
G01X2099266Y599256D02*
X2100196Y597797D01*
X2101436Y596964D01*
X2102831Y596756D01*
X2104071Y596964D01*
X2105311Y598006D01*
X2106086Y599256D01*
X2106241Y600506D01*
X2105931Y601964D01*
X2104846Y603006D01*
X2103761Y603423D01*
X2102366D01*
G01X2103761D02*
X2104691Y604048D01*
X2105466Y605089D01*
X2105776Y606339D01*
X2105466Y607589D01*
X2104691Y608631D01*
X2103296Y609256D01*
X2101901Y609048D01*
X2100506Y608214D01*
G01X2116936Y596756D02*
Y609256D01*
X2111201Y600298D01*
X2118951D01*
G01X2110736Y624856D02*
Y637356D01*
X2105001Y628398D01*
X2112751D01*
G01X2102676Y681056D02*
Y693556D01*
X2100816Y691056D01*
G01Y681056D02*
X2104536D01*
G01X2116936D02*
Y693556D01*
X2111201Y684598D01*
X2118951D01*
G01X2102676Y652956D02*
Y665456D01*
X2100816Y662956D01*
G01Y652956D02*
X2104536D01*
G01X2112131Y663373D02*
X2113061Y664622D01*
X2114146Y665248D01*
X2115386Y665456D01*
X2116936Y665039D01*
X2118021Y663998D01*
X2118331Y662748D01*
X2118176Y661497D01*
X2117556Y660456D01*
X2114456Y658373D01*
X2113061Y656914D01*
X2112131Y654831D01*
X2111821Y652956D01*
X2118331D01*
G01X2105466Y711656D02*
X2106396Y710197D01*
X2107636Y709364D01*
X2109031Y709156D01*
X2110271Y709364D01*
X2111511Y710406D01*
X2112286Y711656D01*
X2112441Y712906D01*
X2112131Y714364D01*
X2111046Y715406D01*
X2109961Y715823D01*
X2108566D01*
G01X2109961D02*
X2110891Y716448D01*
X2111666Y717489D01*
X2111976Y718739D01*
X2111666Y719989D01*
X2110891Y721031D01*
X2109496Y721656D01*
X2108101Y721448D01*
X2106706Y720614D01*
G01X2099266Y739756D02*
X2100196Y738297D01*
X2101436Y737464D01*
X2102831Y737256D01*
X2104071Y737464D01*
X2105311Y738506D01*
X2106086Y739756D01*
X2106241Y741006D01*
X2105931Y742464D01*
X2104846Y743506D01*
X2103761Y743923D01*
X2102366D01*
G01X2103761D02*
X2104691Y744548D01*
X2105466Y745589D01*
X2105776Y746839D01*
X2105466Y748089D01*
X2104691Y749131D01*
X2103296Y749756D01*
X2101901Y749548D01*
X2100506Y748714D01*
G01X2112131Y742464D02*
X2113216Y743923D01*
X2114146Y744756D01*
X2115386Y745173D01*
X2116471Y744756D01*
X2117246Y743923D01*
X2117866Y742673D01*
X2118021Y741214D01*
X2117866Y739964D01*
X2117246Y738714D01*
X2116316Y737673D01*
X2115231Y737256D01*
X2113991Y737673D01*
X2112906Y738922D01*
X2112286Y740798D01*
X2112131Y742881D01*
X2112441Y745589D01*
X2112906Y747048D01*
X2113681Y748506D01*
X2114766Y749548D01*
X2115851Y749756D01*
X2116936Y749339D01*
X2117711Y748298D01*
G01X2093066Y767856D02*
X2093996Y766397D01*
X2095236Y765564D01*
X2096631Y765356D01*
X2097871Y765564D01*
X2099111Y766606D01*
X2099886Y767856D01*
X2100041Y769106D01*
X2099731Y770564D01*
X2098646Y771606D01*
X2097561Y772023D01*
X2096166D01*
G01X2097561D02*
X2098491Y772648D01*
X2099266Y773689D01*
X2099576Y774939D01*
X2099266Y776189D01*
X2098491Y777231D01*
X2097096Y777856D01*
X2095701Y777648D01*
X2094306Y776814D01*
G01X2105931Y770564D02*
X2107016Y772023D01*
X2107946Y772856D01*
X2109186Y773273D01*
X2110271Y772856D01*
X2111046Y772023D01*
X2111666Y770773D01*
X2111821Y769314D01*
X2111666Y768064D01*
X2111046Y766814D01*
X2110116Y765773D01*
X2109031Y765356D01*
X2107791Y765773D01*
X2106706Y767022D01*
X2106086Y768898D01*
X2105931Y770981D01*
X2106241Y773689D01*
X2106706Y775148D01*
X2107481Y776606D01*
X2108566Y777648D01*
X2109651Y777856D01*
X2110736Y777439D01*
X2111511Y776398D01*
G01X2117866Y767231D02*
X2118796Y766189D01*
X2119881Y765564D01*
X2121276Y765356D01*
X2122671Y765773D01*
X2123756Y766606D01*
X2124531Y768064D01*
X2124686Y769731D01*
X2124376Y771398D01*
X2123601Y772439D01*
X2122516Y773273D01*
X2121431Y773481D01*
X2120346Y773273D01*
X2118951Y772439D01*
X2119416Y777856D01*
X2123601D01*
G01X2093531Y803873D02*
X2094461Y805122D01*
X2095546Y805748D01*
X2096786Y805956D01*
X2098336Y805539D01*
X2099421Y804498D01*
X2099731Y803248D01*
X2099576Y801997D01*
X2098956Y800956D01*
X2095856Y798873D01*
X2094461Y797414D01*
X2093531Y795331D01*
X2093221Y793456D01*
X2099731D01*
G01X2108876D02*
X2109961Y793664D01*
X2111201Y794289D01*
X2111976Y795331D01*
X2112286Y796789D01*
X2111976Y798247D01*
X2111046Y799498D01*
X2109651Y800123D01*
X2108101D01*
X2107171Y800539D01*
X2106396Y801581D01*
X2106086Y803039D01*
X2106551Y804498D01*
X2107636Y805539D01*
X2108876Y805956D01*
X2110116Y805539D01*
X2111201Y804498D01*
X2111666Y803039D01*
X2111356Y801581D01*
X2110581Y800539D01*
X2109651Y800123D01*
X2108101D01*
X2106706Y799498D01*
X2105776Y798247D01*
X2105466Y796789D01*
X2105776Y795331D01*
X2106551Y794289D01*
X2107791Y793664D01*
X2108876Y793456D01*
G01X2121276D02*
X2122361Y793664D01*
X2123601Y794289D01*
X2124376Y795331D01*
X2124686Y796789D01*
X2124376Y798247D01*
X2123446Y799498D01*
X2122051Y800123D01*
X2120501D01*
X2119571Y800539D01*
X2118796Y801581D01*
X2118486Y803039D01*
X2118951Y804498D01*
X2120036Y805539D01*
X2121276Y805956D01*
X2122516Y805539D01*
X2123601Y804498D01*
X2124066Y803039D01*
X2123756Y801581D01*
X2122981Y800539D01*
X2122051Y800123D01*
X2120501D01*
X2119106Y799498D01*
X2118176Y798247D01*
X2117866Y796789D01*
X2118176Y795331D01*
X2118951Y794289D01*
X2120191Y793664D01*
X2121276Y793456D01*
G01X2106241Y823014D02*
X2107326Y821973D01*
X2108566Y821556D01*
X2109806Y821973D01*
X2110891Y823222D01*
X2111666Y825098D01*
X2111976Y826973D01*
Y829264D01*
X2111666Y831139D01*
X2110891Y832806D01*
X2109961Y833639D01*
X2108876Y834056D01*
X2107636Y833639D01*
X2106706Y832806D01*
X2106086Y831556D01*
X2105776Y829889D01*
X2106086Y828431D01*
X2106861Y826973D01*
X2107791Y826139D01*
X2108876Y825931D01*
X2110116Y826347D01*
X2111046Y827389D01*
X2111976Y829264D01*
G01X2096476Y907406D02*
X2095236Y907614D01*
X2094151Y908447D01*
X2093221Y909698D01*
X2092601Y911156D01*
X2092291Y912823D01*
Y914489D01*
X2092601Y916156D01*
X2093221Y917614D01*
X2094151Y918864D01*
X2095236Y919698D01*
X2096476Y919906D01*
X2097716Y919698D01*
X2098801Y918864D01*
X2099731Y917614D01*
X2100351Y916156D01*
X2100661Y914489D01*
Y912823D01*
X2100351Y911156D01*
X2099731Y909698D01*
X2098801Y908447D01*
X2097716Y907614D01*
X2096476Y907406D01*
G01X2097716Y910739D02*
X2099576Y907406D01*
G01X2108876Y919906D02*
Y907406D01*
G01X2105311Y919906D02*
X2112441D01*
G01X2121276Y907406D02*
Y913031D01*
X2118176Y919906D01*
G01X2124376D02*
X2121276Y913031D01*
G01X1425733Y-51181D02*
X-29385D01*
G01X-33322Y-47244D02*
G03X-29385Y-51181I3937J0D01*
G01X-33322Y-47244D02*
Y893701D01*
G01X-7874Y102402D02*
Y212205D01*
G01Y102402D02*
G03X0Y94528I7874J0D01*
G01Y212205D02*
G03X-7874I-3937J0D01*
G01Y237402D02*
G03X0I3937J-1D01*
G01X-7874D02*
Y406693D01*
G01X0D02*
G03X-7874I-3937J0D01*
G01Y431890D02*
G03X0I3937J0D01*
G01X-7874D02*
Y601181D01*
G01X0D02*
G03X-7874I-3937J0D01*
G01Y626378D02*
Y795669D01*
G01Y626378D02*
G03X0I3937J0D01*
G01Y795669D02*
G03X-7874I-3937J0D01*
G01Y820866D02*
G03X0I3937J0D01*
G01X-7874Y844488D02*
Y820866D01*
G01X-3937Y848425D02*
G03X-7874Y844488I0J-3937D01*
G01X93307Y848425D02*
X-3937D01*
G01X-29385Y897638D02*
G03X-33322Y893701I0J-3937D01*
G01X-29385Y897638D02*
X93307D01*
G01X98425Y94528D02*
X0D01*
G01X1400000Y36220D02*
G03X1398031Y38189I-1969J0D01*
G01X1396654D01*
G02X1394685Y40157I0J1969D01*
G01Y71654D01*
G02X1396654Y73622I1969J-1D01*
G01X1398031D01*
G03X1400000Y75591I0J1969D01*
G01Y836614D01*
G03X1396063Y840551I-3937J0D01*
G01X1368504D01*
G02X1363386Y845669I0J5118D01*
G01Y871654D01*
G03X1361417Y873622I-1969J-1D01*
G01X1358268D01*
G02X1356299Y875591I0J1969D01*
G01Y892521D01*
X1352363Y897638D01*
X1218110D01*
X1214173Y892520D01*
Y875984D01*
G02X1205512I-4331J0D01*
G01Y892520D01*
X1201575Y897638D01*
X1029528D01*
X1025591Y892520D01*
Y875591D01*
G02X1023622Y873622I-1969J0D01*
G01X1020472D01*
G03X1018504Y871654I0J-1968D01*
G01Y845669D01*
G02X1013386Y840551I-5118J0D01*
G01X1008433D01*
G03X988748Y820866I0J-19685D01*
G01Y650669D01*
G02X983748Y645669I-5000J0D01*
G01X926819D01*
G02X921819Y650669I0J5000D01*
G01Y820866D01*
G03X902134Y840551I-19685J0D01*
G01X872441D01*
G02X867323Y845669I0J5118D01*
G01Y871654D01*
G03X865354Y873622I-1969J-1D01*
G01X862205D01*
G02X860236Y875591I0J1969D01*
G01Y892521D01*
X856300Y897638D01*
X722048D01*
X718110Y892519D01*
Y875984D01*
G02X709449I-4331J0D01*
G01Y892520D01*
X705512Y897638D01*
X533465D01*
X529528Y892520D01*
Y875591D01*
G02X527559Y873622I-1969J0D01*
G01X524409D01*
G03X522441Y871654I0J-1968D01*
G01Y845669D01*
G02X517323Y840551I-5118J0D01*
G01X455118D01*
G02X450000Y845669I0J5118D01*
G01Y871654D01*
G03X448031Y873622I-1968J0D01*
G01X444882D01*
G02X442913Y875591I0J1969D01*
G01Y892521D01*
X438977Y897638D01*
X304725D01*
X300787Y892519D01*
Y875984D01*
G02X292126I-4331J0D01*
G01Y892521D01*
X288190Y897638D01*
X116142D01*
X112205Y892520D01*
Y875591D01*
G02X110236Y873622I-1969J0D01*
G01X107087D01*
G03X105118Y871654I0J-1969D01*
G01Y845669D01*
G02X100000Y840551I-5118J0D01*
G01X3937D01*
G03X0Y836614I0J-3937D01*
G01Y110276D01*
G03X7874Y102402I7874J0D01*
G01X196654D01*
G02X204528Y94528I0J-7874D01*
G01Y7874D01*
G03X212402Y0I7874J0D01*
G01X471014D01*
G02X478888Y-7874I0J-7874D01*
G01Y-11811D01*
G03X486762Y-19685I7874J0D01*
G01X1302165D01*
G03X1306102Y-15748I0J3937D01*
G01Y-3937D01*
G02X1310039Y0I3937J0D01*
G01X1396063D01*
G03X1400000Y3937I0J3937D01*
G01Y36220D01*
G01X93307Y848425D02*
G03X97244Y852362I0J3937D01*
G01Y893701D02*
Y852362D01*
G01Y893701D02*
G03X93307Y897638I-3937J0D01*
G01X192717Y94528D02*
X123622D01*
G01Y102402D02*
G03Y94528I0J-3937D01*
G01X98425D02*
G03Y102402I0J3937D01*
G01X196654Y0D02*
G03X204528Y-7874I7874J0D01*
G01X196654Y0D02*
Y29961D01*
G01X204528D02*
G03X196654I-3937J0D01*
G01Y55157D02*
Y90591D01*
G01Y55157D02*
G03X204528I3937J0D01*
G01X196654Y90591D02*
G03X192717Y94528I-3937J0D01*
G01X232077Y-7874D02*
G03Y0I0J3937D01*
G01Y-7874D02*
X204528D01*
G01X434439D02*
X257274D01*
G01Y0D02*
G03Y-7874I0J-3937D01*
G01X365945Y38188D02*
G03X367914Y40156I0J1969D01*
G01X354134D02*
G03X356103Y38188I1969J1D01*
G01D02*
X365945D01*
G01X354134Y71653D02*
Y40156D01*
G01X367914Y71653D02*
G03X365945Y73621I-1969J-1D01*
G01X356103D02*
G03X354134Y71653I0J-1969D01*
G01X365945Y73621D02*
X356103D01*
G01X367914Y40156D02*
Y71653D01*
G01X434439Y-7874D02*
G03Y0I0J3937D01*
G01X471014Y-15748D02*
G03X463140Y-7874I-7874J0D01*
G01D02*
X459636D01*
G01Y0D02*
G03Y-7874I0J-3937D01*
G01X707234Y-27559D02*
X478888D01*
G01X471014Y-19685D02*
G03X478888Y-27559I7874J0D01*
G01X471014Y-19685D02*
Y-15748D01*
G01X495390Y-17914D02*
Y-13914D01*
X496990D01*
X497523Y-14114D01*
X497923Y-14581D01*
X498056Y-15114D01*
X497923Y-15647D01*
X497590Y-16047D01*
X496990Y-16247D01*
X495390D01*
G01X500390Y-17914D02*
Y-15247D01*
G01Y-15781D02*
X500723Y-15514D01*
X501056Y-15314D01*
X501523Y-15247D01*
X501856Y-15314D01*
X502256Y-15514D01*
G01X504923Y-16114D02*
X507056D01*
X506856Y-15647D01*
X506523Y-15381D01*
X506056Y-15247D01*
X505590Y-15314D01*
X505190Y-15514D01*
X504923Y-15981D01*
X504790Y-16381D01*
Y-16781D01*
X504923Y-17181D01*
X505256Y-17581D01*
X505656Y-17847D01*
X506123Y-17914D01*
X506590Y-17781D01*
X507056Y-17381D01*
G01X509523Y-17447D02*
X509856Y-17714D01*
X510323Y-17914D01*
X510723D01*
X511123Y-17781D01*
X511390Y-17581D01*
X511523Y-17314D01*
X511456Y-16914D01*
X511190Y-16714D01*
X509990Y-16314D01*
X509723Y-15847D01*
X509856Y-15514D01*
X510123Y-15314D01*
X510523Y-15247D01*
X510923Y-15314D01*
X511323Y-15514D01*
G01X514123Y-17447D02*
X514456Y-17714D01*
X514923Y-17914D01*
X515323D01*
X515723Y-17781D01*
X515990Y-17581D01*
X516123Y-17314D01*
X516056Y-16914D01*
X515790Y-16714D01*
X514590Y-16314D01*
X514323Y-15847D01*
X514456Y-15514D01*
X514723Y-15314D01*
X515123Y-15247D01*
X515523Y-15314D01*
X515923Y-15514D01*
G01X518856Y-16581D02*
X520590D01*
G01X523923Y-17914D02*
Y-14514D01*
X524056Y-14181D01*
X524323Y-13981D01*
X524723Y-13914D01*
X525123Y-14047D01*
X525323Y-14381D01*
G01X524523Y-15514D02*
X523190D01*
G01X528923Y-15247D02*
Y-17914D01*
G01Y-14181D02*
X528790Y-14114D01*
Y-13981D01*
X528923Y-13914D01*
X529056Y-13981D01*
Y-14114D01*
X528923Y-14181D01*
G01X533523Y-13914D02*
Y-17914D01*
G01X532590Y-15247D02*
X534456D01*
G01X541390Y-17914D02*
Y-13914D01*
X542990D01*
X543523Y-14114D01*
X543923Y-14581D01*
X544056Y-15114D01*
X543923Y-15647D01*
X543590Y-16047D01*
X542990Y-16247D01*
X541390D01*
G01X547323Y-13914D02*
Y-17914D01*
G01X545790Y-13914D02*
X548856D01*
G01X550523Y-17914D02*
Y-13914D01*
G01X553323D02*
Y-17914D01*
G01Y-15914D02*
X550523D01*
G01X559990Y-17914D02*
Y-13914D01*
G01X562123Y-15247D02*
X559990Y-16781D01*
G01X560856Y-16181D02*
X562256Y-17914D01*
G01X564723Y-16114D02*
X566856D01*
X566656Y-15647D01*
X566323Y-15381D01*
X565856Y-15247D01*
X565390Y-15314D01*
X564990Y-15514D01*
X564723Y-15981D01*
X564590Y-16381D01*
Y-16781D01*
X564723Y-17181D01*
X565056Y-17581D01*
X565456Y-17847D01*
X565923Y-17914D01*
X566390Y-17781D01*
X566856Y-17381D01*
G01X569323Y-16114D02*
X571456D01*
X571256Y-15647D01*
X570923Y-15381D01*
X570456Y-15247D01*
X569990Y-15314D01*
X569590Y-15514D01*
X569323Y-15981D01*
X569190Y-16381D01*
Y-16781D01*
X569323Y-17181D01*
X569656Y-17581D01*
X570056Y-17847D01*
X570523Y-17914D01*
X570990Y-17781D01*
X571456Y-17381D01*
G01X573723Y-19247D02*
Y-15247D01*
G01Y-15847D02*
X574056Y-15514D01*
X574390Y-15314D01*
X574923Y-15247D01*
X575390Y-15314D01*
X575856Y-15647D01*
X576056Y-16114D01*
X576123Y-16581D01*
X576056Y-17047D01*
X575856Y-17514D01*
X575456Y-17781D01*
X574923Y-17914D01*
X574456Y-17847D01*
X573990Y-17647D01*
X573723Y-17381D01*
G01X582990Y-17914D02*
Y-13914D01*
G01Y-15847D02*
X583323Y-15514D01*
X583656Y-15314D01*
X584190Y-15247D01*
X584590Y-15314D01*
X585056Y-15581D01*
X585256Y-15981D01*
Y-17914D01*
G01X588723D02*
X588323Y-17847D01*
X587923Y-17581D01*
X587656Y-17114D01*
X587523Y-16581D01*
X587656Y-16047D01*
X587923Y-15581D01*
X588323Y-15314D01*
X588723Y-15247D01*
X589123Y-15314D01*
X589523Y-15581D01*
X589790Y-16047D01*
X589856Y-16581D01*
X589790Y-17114D01*
X589523Y-17581D01*
X589123Y-17847D01*
X588723Y-17914D01*
G01X593323D02*
Y-13914D01*
G01X596923Y-16114D02*
X599056D01*
X598856Y-15647D01*
X598523Y-15381D01*
X598056Y-15247D01*
X597590Y-15314D01*
X597190Y-15514D01*
X596923Y-15981D01*
X596790Y-16381D01*
Y-16781D01*
X596923Y-17181D01*
X597256Y-17581D01*
X597656Y-17847D01*
X598123Y-17914D01*
X598590Y-17781D01*
X599056Y-17381D01*
G01X606123Y-17447D02*
X606456Y-17714D01*
X606923Y-17914D01*
X607323D01*
X607723Y-17781D01*
X607990Y-17581D01*
X608123Y-17314D01*
X608056Y-16914D01*
X607790Y-16714D01*
X606590Y-16314D01*
X606323Y-15847D01*
X606456Y-15514D01*
X606723Y-15314D01*
X607123Y-15247D01*
X607523Y-15314D01*
X607923Y-15514D01*
G01X611723Y-15247D02*
Y-17914D01*
G01Y-14181D02*
X611590Y-14114D01*
Y-13981D01*
X611723Y-13914D01*
X611856Y-13981D01*
Y-14114D01*
X611723Y-14181D01*
G01X615323Y-15247D02*
X617323D01*
X615323Y-17914D01*
X617323D01*
G01X619923Y-16114D02*
X622056D01*
X621856Y-15647D01*
X621523Y-15381D01*
X621056Y-15247D01*
X620590Y-15314D01*
X620190Y-15514D01*
X619923Y-15981D01*
X619790Y-16381D01*
Y-16781D01*
X619923Y-17181D01*
X620256Y-17581D01*
X620656Y-17847D01*
X621123Y-17914D01*
X621590Y-17781D01*
X622056Y-17381D01*
G01X630123Y-13914D02*
Y-17914D01*
G01X629190Y-15247D02*
X631056D01*
G01X634723Y-17914D02*
X634323Y-17847D01*
X633923Y-17581D01*
X633656Y-17114D01*
X633523Y-16581D01*
X633656Y-16047D01*
X633923Y-15581D01*
X634323Y-15314D01*
X634723Y-15247D01*
X635123Y-15314D01*
X635523Y-15581D01*
X635790Y-16047D01*
X635856Y-16581D01*
X635790Y-17114D01*
X635523Y-17581D01*
X635123Y-17847D01*
X634723Y-17914D01*
G01X639323D02*
Y-13914D01*
G01X642923Y-16114D02*
X645056D01*
X644856Y-15647D01*
X644523Y-15381D01*
X644056Y-15247D01*
X643590Y-15314D01*
X643190Y-15514D01*
X642923Y-15981D01*
X642790Y-16381D01*
Y-16781D01*
X642923Y-17181D01*
X643256Y-17581D01*
X643656Y-17847D01*
X644123Y-17914D01*
X644590Y-17781D01*
X645056Y-17381D01*
G01X647590Y-17914D02*
Y-15247D01*
G01Y-15781D02*
X647923Y-15514D01*
X648256Y-15314D01*
X648723Y-15247D01*
X649056Y-15314D01*
X649456Y-15514D01*
G01X654323Y-17914D02*
Y-15247D01*
G01Y-15714D02*
X654056Y-15447D01*
X653656Y-15314D01*
X653190Y-15247D01*
X652723Y-15381D01*
X652323Y-15647D01*
X652056Y-16047D01*
X651923Y-16581D01*
X652056Y-17114D01*
X652323Y-17514D01*
X652723Y-17781D01*
X653190Y-17914D01*
X653656Y-17847D01*
X654056Y-17647D01*
X654323Y-17381D01*
G01X656590Y-17914D02*
Y-15247D01*
G01Y-15914D02*
X656856Y-15581D01*
X657256Y-15314D01*
X657790Y-15247D01*
X658256Y-15314D01*
X658656Y-15581D01*
X658856Y-16047D01*
Y-17914D01*
G01X663390Y-15581D02*
X662923Y-15314D01*
X662523Y-15247D01*
X661990Y-15381D01*
X661590Y-15647D01*
X661323Y-16114D01*
X661256Y-16581D01*
X661323Y-17047D01*
X661590Y-17447D01*
X661990Y-17781D01*
X662523Y-17914D01*
X662990Y-17781D01*
X663390Y-17514D01*
G01X665923Y-16114D02*
X668056D01*
X667856Y-15647D01*
X667523Y-15381D01*
X667056Y-15247D01*
X666590Y-15314D01*
X666190Y-15514D01*
X665923Y-15981D01*
X665790Y-16381D01*
Y-16781D01*
X665923Y-17181D01*
X666256Y-17581D01*
X666656Y-17847D01*
X667123Y-17914D01*
X667590Y-17781D01*
X668056Y-17381D01*
G01X675390Y-16581D02*
X676990D01*
G01X676123Y-15714D02*
Y-17447D01*
G01X679523Y-18047D02*
X681923Y-13914D01*
G01X684456Y-16581D02*
X686190D01*
G01X688656Y-14581D02*
X689056Y-14181D01*
X689523Y-13981D01*
X690056Y-13914D01*
X690723Y-14047D01*
X691190Y-14381D01*
X691323Y-14781D01*
X691256Y-15181D01*
X690990Y-15514D01*
X689656Y-16181D01*
X689056Y-16647D01*
X688656Y-17314D01*
X688523Y-17914D01*
X691323D01*
G01X697123D02*
Y-15247D01*
G01Y-15981D02*
X697323Y-15647D01*
X697656Y-15381D01*
X698123Y-15247D01*
X698590Y-15381D01*
X698923Y-15647D01*
X699123Y-15981D01*
Y-17914D01*
G01Y-15981D02*
X699323Y-15647D01*
X699656Y-15381D01*
X700123Y-15247D01*
X700590Y-15381D01*
X700923Y-15647D01*
X701123Y-16047D01*
Y-17914D01*
G01X703723Y-15247D02*
Y-17914D01*
G01Y-14181D02*
X703590Y-14114D01*
Y-13981D01*
X703723Y-13914D01*
X703856Y-13981D01*
Y-14114D01*
X703723Y-14181D01*
G01X708323Y-17914D02*
Y-13914D01*
G01X511709Y109057D02*
Y-2915D01*
X690137D01*
Y109057D01*
X511709D01*
G01X604923Y-3480D02*
X602923Y-5480D01*
X606923D01*
X604923Y-3480D01*
Y-15080D01*
G01X870226Y-27559D02*
X732431D01*
G01Y-19685D02*
G03Y-27559I0J-3937D01*
G01X707234D02*
G03Y-19685I0J3937D01*
G01X870226Y-27559D02*
G03Y-19685I1J3937D01*
G01X1072589Y-27559D02*
X895423D01*
G01Y-19685D02*
G03Y-27559I0J-3937D01*
G01X1072589D02*
G03Y-19685I0J3937D01*
G01X1097785D02*
G03Y-27559I1J-3937D01*
G01X1336086Y-8662D02*
X1318701D01*
G03X1314764Y-12599I0J-3937D01*
G01Y-23622D01*
G02X1310827Y-27559I-3937J0D01*
G01X1097785D01*
G01X1097752Y-17914D02*
Y-13914D01*
X1099352D01*
X1099885Y-14114D01*
X1100285Y-14581D01*
X1100418Y-15114D01*
X1100285Y-15647D01*
X1099952Y-16047D01*
X1099352Y-16247D01*
X1097752D01*
G01X1102752Y-17914D02*
Y-15247D01*
G01Y-15781D02*
X1103085Y-15514D01*
X1103418Y-15314D01*
X1103885Y-15247D01*
X1104218Y-15314D01*
X1104618Y-15514D01*
G01X1107285Y-16114D02*
X1109418D01*
X1109218Y-15647D01*
X1108885Y-15381D01*
X1108418Y-15247D01*
X1107952Y-15314D01*
X1107552Y-15514D01*
X1107285Y-15981D01*
X1107152Y-16381D01*
Y-16781D01*
X1107285Y-17181D01*
X1107618Y-17581D01*
X1108018Y-17847D01*
X1108485Y-17914D01*
X1108952Y-17781D01*
X1109418Y-17381D01*
G01X1111885Y-17447D02*
X1112218Y-17714D01*
X1112685Y-17914D01*
X1113085D01*
X1113485Y-17781D01*
X1113752Y-17581D01*
X1113885Y-17314D01*
X1113818Y-16914D01*
X1113552Y-16714D01*
X1112352Y-16314D01*
X1112085Y-15847D01*
X1112218Y-15514D01*
X1112485Y-15314D01*
X1112885Y-15247D01*
X1113285Y-15314D01*
X1113685Y-15514D01*
G01X1116485Y-17447D02*
X1116818Y-17714D01*
X1117285Y-17914D01*
X1117685D01*
X1118085Y-17781D01*
X1118352Y-17581D01*
X1118485Y-17314D01*
X1118418Y-16914D01*
X1118152Y-16714D01*
X1116952Y-16314D01*
X1116685Y-15847D01*
X1116818Y-15514D01*
X1117085Y-15314D01*
X1117485Y-15247D01*
X1117885Y-15314D01*
X1118285Y-15514D01*
G01X1121218Y-16581D02*
X1122952D01*
G01X1126285Y-17914D02*
Y-14514D01*
X1126418Y-14181D01*
X1126685Y-13981D01*
X1127085Y-13914D01*
X1127485Y-14047D01*
X1127685Y-14381D01*
G01X1126885Y-15514D02*
X1125552D01*
G01X1131285Y-15247D02*
Y-17914D01*
G01Y-14181D02*
X1131152Y-14114D01*
Y-13981D01*
X1131285Y-13914D01*
X1131418Y-13981D01*
Y-14114D01*
X1131285Y-14181D01*
G01X1135885Y-13914D02*
Y-17914D01*
G01X1134952Y-15247D02*
X1136818D01*
G01X1143752Y-17914D02*
Y-13914D01*
X1145352D01*
X1145885Y-14114D01*
X1146285Y-14581D01*
X1146418Y-15114D01*
X1146285Y-15647D01*
X1145952Y-16047D01*
X1145352Y-16247D01*
X1143752D01*
G01X1149685Y-13914D02*
Y-17914D01*
G01X1148152Y-13914D02*
X1151218D01*
G01X1152885Y-17914D02*
Y-13914D01*
G01X1155685D02*
Y-17914D01*
G01Y-15914D02*
X1152885D01*
G01X1162352Y-17914D02*
Y-13914D01*
G01X1164485Y-15247D02*
X1162352Y-16781D01*
G01X1163218Y-16181D02*
X1164618Y-17914D01*
G01X1167085Y-16114D02*
X1169218D01*
X1169018Y-15647D01*
X1168685Y-15381D01*
X1168218Y-15247D01*
X1167752Y-15314D01*
X1167352Y-15514D01*
X1167085Y-15981D01*
X1166952Y-16381D01*
Y-16781D01*
X1167085Y-17181D01*
X1167418Y-17581D01*
X1167818Y-17847D01*
X1168285Y-17914D01*
X1168752Y-17781D01*
X1169218Y-17381D01*
G01X1171685Y-16114D02*
X1173818D01*
X1173618Y-15647D01*
X1173285Y-15381D01*
X1172818Y-15247D01*
X1172352Y-15314D01*
X1171952Y-15514D01*
X1171685Y-15981D01*
X1171552Y-16381D01*
Y-16781D01*
X1171685Y-17181D01*
X1172018Y-17581D01*
X1172418Y-17847D01*
X1172885Y-17914D01*
X1173352Y-17781D01*
X1173818Y-17381D01*
G01X1176085Y-19247D02*
Y-15247D01*
G01Y-15847D02*
X1176418Y-15514D01*
X1176752Y-15314D01*
X1177285Y-15247D01*
X1177752Y-15314D01*
X1178218Y-15647D01*
X1178418Y-16114D01*
X1178485Y-16581D01*
X1178418Y-17047D01*
X1178218Y-17514D01*
X1177818Y-17781D01*
X1177285Y-17914D01*
X1176818Y-17847D01*
X1176352Y-17647D01*
X1176085Y-17381D01*
G01X1185352Y-17914D02*
Y-13914D01*
G01Y-15847D02*
X1185685Y-15514D01*
X1186018Y-15314D01*
X1186552Y-15247D01*
X1186952Y-15314D01*
X1187418Y-15581D01*
X1187618Y-15981D01*
Y-17914D01*
G01X1191085D02*
X1190685Y-17847D01*
X1190285Y-17581D01*
X1190018Y-17114D01*
X1189885Y-16581D01*
X1190018Y-16047D01*
X1190285Y-15581D01*
X1190685Y-15314D01*
X1191085Y-15247D01*
X1191485Y-15314D01*
X1191885Y-15581D01*
X1192152Y-16047D01*
X1192218Y-16581D01*
X1192152Y-17114D01*
X1191885Y-17581D01*
X1191485Y-17847D01*
X1191085Y-17914D01*
G01X1195685D02*
Y-13914D01*
G01X1199285Y-16114D02*
X1201418D01*
X1201218Y-15647D01*
X1200885Y-15381D01*
X1200418Y-15247D01*
X1199952Y-15314D01*
X1199552Y-15514D01*
X1199285Y-15981D01*
X1199152Y-16381D01*
Y-16781D01*
X1199285Y-17181D01*
X1199618Y-17581D01*
X1200018Y-17847D01*
X1200485Y-17914D01*
X1200952Y-17781D01*
X1201418Y-17381D01*
G01X1208485Y-17447D02*
X1208818Y-17714D01*
X1209285Y-17914D01*
X1209685D01*
X1210085Y-17781D01*
X1210352Y-17581D01*
X1210485Y-17314D01*
X1210418Y-16914D01*
X1210152Y-16714D01*
X1208952Y-16314D01*
X1208685Y-15847D01*
X1208818Y-15514D01*
X1209085Y-15314D01*
X1209485Y-15247D01*
X1209885Y-15314D01*
X1210285Y-15514D01*
G01X1214085Y-15247D02*
Y-17914D01*
G01Y-14181D02*
X1213952Y-14114D01*
Y-13981D01*
X1214085Y-13914D01*
X1214218Y-13981D01*
Y-14114D01*
X1214085Y-14181D01*
G01X1217685Y-15247D02*
X1219685D01*
X1217685Y-17914D01*
X1219685D01*
G01X1222285Y-16114D02*
X1224418D01*
X1224218Y-15647D01*
X1223885Y-15381D01*
X1223418Y-15247D01*
X1222952Y-15314D01*
X1222552Y-15514D01*
X1222285Y-15981D01*
X1222152Y-16381D01*
Y-16781D01*
X1222285Y-17181D01*
X1222618Y-17581D01*
X1223018Y-17847D01*
X1223485Y-17914D01*
X1223952Y-17781D01*
X1224418Y-17381D01*
G01X1232485Y-13914D02*
Y-17914D01*
G01X1231552Y-15247D02*
X1233418D01*
G01X1237085Y-17914D02*
X1236685Y-17847D01*
X1236285Y-17581D01*
X1236018Y-17114D01*
X1235885Y-16581D01*
X1236018Y-16047D01*
X1236285Y-15581D01*
X1236685Y-15314D01*
X1237085Y-15247D01*
X1237485Y-15314D01*
X1237885Y-15581D01*
X1238152Y-16047D01*
X1238218Y-16581D01*
X1238152Y-17114D01*
X1237885Y-17581D01*
X1237485Y-17847D01*
X1237085Y-17914D01*
G01X1241685D02*
Y-13914D01*
G01X1245285Y-16114D02*
X1247418D01*
X1247218Y-15647D01*
X1246885Y-15381D01*
X1246418Y-15247D01*
X1245952Y-15314D01*
X1245552Y-15514D01*
X1245285Y-15981D01*
X1245152Y-16381D01*
Y-16781D01*
X1245285Y-17181D01*
X1245618Y-17581D01*
X1246018Y-17847D01*
X1246485Y-17914D01*
X1246952Y-17781D01*
X1247418Y-17381D01*
G01X1249952Y-17914D02*
Y-15247D01*
G01Y-15781D02*
X1250285Y-15514D01*
X1250618Y-15314D01*
X1251085Y-15247D01*
X1251418Y-15314D01*
X1251818Y-15514D01*
G01X1256685Y-17914D02*
Y-15247D01*
G01Y-15714D02*
X1256418Y-15447D01*
X1256018Y-15314D01*
X1255552Y-15247D01*
X1255085Y-15381D01*
X1254685Y-15647D01*
X1254418Y-16047D01*
X1254285Y-16581D01*
X1254418Y-17114D01*
X1254685Y-17514D01*
X1255085Y-17781D01*
X1255552Y-17914D01*
X1256018Y-17847D01*
X1256418Y-17647D01*
X1256685Y-17381D01*
G01X1258952Y-17914D02*
Y-15247D01*
G01Y-15914D02*
X1259218Y-15581D01*
X1259618Y-15314D01*
X1260152Y-15247D01*
X1260618Y-15314D01*
X1261018Y-15581D01*
X1261218Y-16047D01*
Y-17914D01*
G01X1265752Y-15581D02*
X1265285Y-15314D01*
X1264885Y-15247D01*
X1264352Y-15381D01*
X1263952Y-15647D01*
X1263685Y-16114D01*
X1263618Y-16581D01*
X1263685Y-17047D01*
X1263952Y-17447D01*
X1264352Y-17781D01*
X1264885Y-17914D01*
X1265352Y-17781D01*
X1265752Y-17514D01*
G01X1268285Y-16114D02*
X1270418D01*
X1270218Y-15647D01*
X1269885Y-15381D01*
X1269418Y-15247D01*
X1268952Y-15314D01*
X1268552Y-15514D01*
X1268285Y-15981D01*
X1268152Y-16381D01*
Y-16781D01*
X1268285Y-17181D01*
X1268618Y-17581D01*
X1269018Y-17847D01*
X1269485Y-17914D01*
X1269952Y-17781D01*
X1270418Y-17381D01*
G01X1277752Y-16581D02*
X1279352D01*
G01X1278485Y-15714D02*
Y-17447D01*
G01X1281885Y-18047D02*
X1284285Y-13914D01*
G01X1286818Y-16581D02*
X1288552D01*
G01X1291018Y-14581D02*
X1291418Y-14181D01*
X1291885Y-13981D01*
X1292418Y-13914D01*
X1293085Y-14047D01*
X1293552Y-14381D01*
X1293685Y-14781D01*
X1293618Y-15181D01*
X1293352Y-15514D01*
X1292018Y-16181D01*
X1291418Y-16647D01*
X1291018Y-17314D01*
X1290885Y-17914D01*
X1293685D01*
G01X1299485D02*
Y-15247D01*
G01Y-15981D02*
X1299685Y-15647D01*
X1300018Y-15381D01*
X1300485Y-15247D01*
X1300952Y-15381D01*
X1301285Y-15647D01*
X1301485Y-15981D01*
Y-17914D01*
G01Y-15981D02*
X1301685Y-15647D01*
X1302018Y-15381D01*
X1302485Y-15247D01*
X1302952Y-15381D01*
X1303285Y-15647D01*
X1303485Y-16047D01*
Y-17914D01*
G01X1306085Y-15247D02*
Y-17914D01*
G01Y-14181D02*
X1305952Y-14114D01*
Y-13981D01*
X1306085Y-13914D01*
X1306218Y-13981D01*
Y-14114D01*
X1306085Y-14181D01*
G01X1310685Y-17914D02*
Y-13914D01*
G01X1114071Y109057D02*
Y-2915D01*
X1292499D01*
Y109057D01*
X1114071D01*
G01X1207285Y-3480D02*
X1205285Y-5480D01*
X1209285D01*
X1207285Y-3480D01*
Y-15080D01*
G01X1336086Y-8662D02*
G03Y-1I0J4330D01*
G01X1361283D02*
G03Y-8662I0J-4330D01*
G01X1407874Y13026D02*
Y-4725D01*
G02X1403937Y-8662I-3937J0D01*
G01X1361283D01*
G01X1403937Y848425D02*
X1375197D01*
G01X1371260Y852362D02*
G03X1375197Y848425I3937J0D01*
G01X1371260Y852362D02*
Y893701D01*
G01X1375197Y897638D02*
G03X1371260Y893701I0J-3937D01*
G01X1375197Y897638D02*
X1425733D01*
G01X1407874Y30709D02*
Y219685D01*
G01X1400000Y30709D02*
G03X1407874I3937J0D01*
G01Y13026D02*
G03X1400000I-3937J-1D01*
G01X1407874Y219685D02*
G03X1400000I-3937J0D01*
G01Y244882D02*
G03X1407874I3937J0D01*
G01Y414173D02*
Y244882D01*
G01Y608661D02*
Y439370D01*
G01X1400000D02*
G03X1407874I3937J0D01*
G01Y414173D02*
G03X1400000I-3937J0D01*
G01X1407874Y608661D02*
G03X1400000I-3937J0D01*
G01Y626378D02*
G03X1407874I3937J0D01*
G01Y795669D02*
Y626378D01*
G01Y795669D02*
G03X1400000I-3937J0D01*
G01Y820866D02*
G03X1407874I3937J0D01*
G01Y844488D02*
Y820866D01*
G01Y844488D02*
G03X1403937Y848425I-3937J0D01*
G01X1429670Y893701D02*
Y-47244D01*
G01X1425733Y-51181D02*
G03X1429670Y-47244I0J3937D01*
G01Y893701D02*
G03X1425733Y897638I-3937J0D01*
G54D26*
X476614Y167493D03*
Y162493D03*
Y157493D03*
X1708976Y715406D03*
G54D17*
X54378Y237402D03*
X1708976Y378206D03*
G54D18*
X92990Y252362D03*
X116790D03*
X1301120Y173278D03*
Y183908D03*
X1708976Y350106D03*
G54D27*
X473231Y235560D03*
Y274930D03*
X487404Y255245D03*
X1708976Y574906D03*
G54D19*
X122165Y142874D03*
X173897D03*
X1708976Y462506D03*
G54D28*
X514309Y-315D03*
Y52087D03*
X530057Y106457D03*
X557616Y-315D03*
Y52087D03*
X547773Y106457D03*
X600923Y-315D03*
Y52087D03*
X591080Y106457D03*
X573364D03*
X634388D03*
X616671D03*
X644230Y-315D03*
Y52087D03*
X659978Y106457D03*
X687537Y-315D03*
Y52087D03*
X677695Y106457D03*
X1116671Y-315D03*
Y52087D03*
X1132419Y106457D03*
X1159978Y-315D03*
Y52087D03*
X1175726Y106457D03*
X1150135D03*
X1203285Y-315D03*
Y52087D03*
X1193442Y106457D03*
X1246592Y-315D03*
Y52087D03*
X1236750Y106457D03*
X1219033D03*
X1280057D03*
X1262340D03*
X1289899Y-315D03*
Y52087D03*
X1708976Y743506D03*
G54D29*
X535962Y37520D03*
X579269D03*
X622577D03*
X665884D03*
X1138324D03*
X1181631D03*
X1224939D03*
X1268246D03*
X1708976Y490606D03*
M02*
